FILE_TYPE = MACRO_DRAWING;
SET COLOR_WIRE YELLOW;
SET COLOR_PROP MONO;
SET COLOR_DOT WHITE;
SET COLOR_ARC YELLOW;
SET COLOR_BODY GREEN;
SET COLOR_NOTE MONO;
SET PROP_DISPLAY VALUE;
SET PAGE_NUMBER P64;
FORCEADD TAP..1
R 2
(-5500 2125);
FORCEPROP 3 LASTPIN (-5450 2125) SIG_NAME TP_P3E_CPU1_PE1_MP_RXN<4>
J 0
(-5440 2135);
DISPLAY 0.659574 (-5440 2135);
PAINT MONO (-5440 2135);
DISPLAY INVISIBLE (-5440 2135);
FORCEPROP 1 LASTPIN (-5450 2125) BN 4
J 2
(-5438 2133);
DISPLAY 0.617021 (-5438 2133);
PAINT GREEN (-5438 2133);
FORCEPROP 2 LAST CDS_LIB mstr_standard
J 0
(-5500 2125);
PAINT MONO (-5500 2125);
DISPLAY INVISIBLE (-5500 2125);
FORCEPROP 1 LAST BODY_TYPE PLUMBING
J 2
(-5500 2175);
DISPLAY 1.446809 (-5500 2175);
PAINT GREEN (-5500 2175);
DISPLAY INVISIBLE (-5500 2175);
FORCEPROP 1 LAST HDL_TAP TRUE
J 2
(-5825 2000);
DISPLAY 1.446809 (-5825 2000);
PAINT GREEN (-5825 2000);
DISPLAY INVISIBLE (-5825 2000);
FORCEPROP 1 LAST PATH I10
J 2
(-5498 2125);
DISPLAY 0.872340 (-5498 2125);
PAINT GREEN (-5498 2125);
DISPLAY INVISIBLE (-5498 2125);
FORCEADD TAP..1
R 2
(-5500 2175);
FORCEPROP 3 LASTPIN (-5450 2175) SIG_NAME TP_P3E_CPU1_PE1_MP_RXN<5>
J 0
(-5440 2185);
DISPLAY 0.659574 (-5440 2185);
PAINT MONO (-5440 2185);
DISPLAY INVISIBLE (-5440 2185);
FORCEPROP 1 LASTPIN (-5450 2175) BN 5
J 2
(-5438 2183);
DISPLAY 0.617021 (-5438 2183);
PAINT GREEN (-5438 2183);
FORCEPROP 2 LAST CDS_LIB mstr_standard
J 0
(-5500 2175);
PAINT MONO (-5500 2175);
DISPLAY INVISIBLE (-5500 2175);
FORCEPROP 1 LAST BODY_TYPE PLUMBING
J 2
(-5500 2225);
DISPLAY 1.446809 (-5500 2225);
PAINT GREEN (-5500 2225);
DISPLAY INVISIBLE (-5500 2225);
FORCEPROP 1 LAST HDL_TAP TRUE
J 2
(-5825 2050);
DISPLAY 1.446809 (-5825 2050);
PAINT GREEN (-5825 2050);
DISPLAY INVISIBLE (-5825 2050);
FORCEPROP 1 LAST PATH I11
J 2
(-5498 2175);
DISPLAY 0.872340 (-5498 2175);
PAINT GREEN (-5498 2175);
DISPLAY INVISIBLE (-5498 2175);
FORCEADD TAP..1
R 2
(-5500 2275);
FORCEPROP 3 LASTPIN (-5450 2275) SIG_NAME TP_P3E_CPU1_PE1_MP_RXN<7>
J 0
(-5440 2285);
DISPLAY 0.659574 (-5440 2285);
PAINT MONO (-5440 2285);
DISPLAY INVISIBLE (-5440 2285);
FORCEPROP 1 LASTPIN (-5450 2275) BN 7
J 2
(-5438 2283);
DISPLAY 0.617021 (-5438 2283);
PAINT GREEN (-5438 2283);
FORCEPROP 2 LAST CDS_LIB mstr_standard
J 0
(-5500 2275);
PAINT MONO (-5500 2275);
DISPLAY INVISIBLE (-5500 2275);
FORCEPROP 1 LAST BODY_TYPE PLUMBING
J 2
(-5500 2325);
DISPLAY 1.446809 (-5500 2325);
PAINT GREEN (-5500 2325);
DISPLAY INVISIBLE (-5500 2325);
FORCEPROP 1 LAST HDL_TAP TRUE
J 2
(-5825 2150);
DISPLAY 1.446809 (-5825 2150);
PAINT GREEN (-5825 2150);
DISPLAY INVISIBLE (-5825 2150);
FORCEPROP 1 LAST PATH I12
J 2
(-5498 2275);
DISPLAY 0.872340 (-5498 2275);
PAINT GREEN (-5498 2275);
DISPLAY INVISIBLE (-5498 2275);
FORCEADD TAP..1
R 2
(-5500 2225);
FORCEPROP 3 LASTPIN (-5450 2225) SIG_NAME TP_P3E_CPU1_PE1_MP_RXN<6>
J 0
(-5440 2235);
DISPLAY 0.659574 (-5440 2235);
PAINT MONO (-5440 2235);
DISPLAY INVISIBLE (-5440 2235);
FORCEPROP 1 LASTPIN (-5450 2225) BN 6
J 2
(-5438 2233);
DISPLAY 0.617021 (-5438 2233);
PAINT GREEN (-5438 2233);
FORCEPROP 2 LAST CDS_LIB mstr_standard
J 0
(-5500 2225);
PAINT MONO (-5500 2225);
DISPLAY INVISIBLE (-5500 2225);
FORCEPROP 1 LAST BODY_TYPE PLUMBING
J 2
(-5500 2275);
DISPLAY 1.446809 (-5500 2275);
PAINT GREEN (-5500 2275);
DISPLAY INVISIBLE (-5500 2275);
FORCEPROP 1 LAST HDL_TAP TRUE
J 2
(-5825 2100);
DISPLAY 1.446809 (-5825 2100);
PAINT GREEN (-5825 2100);
DISPLAY INVISIBLE (-5825 2100);
FORCEPROP 1 LAST PATH I13
J 2
(-5498 2225);
DISPLAY 0.872340 (-5498 2225);
PAINT GREEN (-5498 2225);
DISPLAY INVISIBLE (-5498 2225);
FORCEADD TAP..1
R 2
(-5350 1975);
FORCEPROP 3 LASTPIN (-5300 1975) SIG_NAME TP_P3E_CPU1_PE1_MP_RXP<2>
J 0
(-5290 1985);
DISPLAY 0.659574 (-5290 1985);
PAINT MONO (-5290 1985);
DISPLAY INVISIBLE (-5290 1985);
FORCEPROP 1 LASTPIN (-5300 1975) BN 2
J 2
(-5288 1983);
DISPLAY 0.617021 (-5288 1983);
PAINT GREEN (-5288 1983);
FORCEPROP 2 LAST CDS_LIB mstr_standard
J 0
(-5350 1975);
PAINT MONO (-5350 1975);
DISPLAY INVISIBLE (-5350 1975);
FORCEPROP 1 LAST BODY_TYPE PLUMBING
J 2
(-5350 2025);
DISPLAY 1.446809 (-5350 2025);
PAINT GREEN (-5350 2025);
DISPLAY INVISIBLE (-5350 2025);
FORCEPROP 1 LAST HDL_TAP TRUE
J 2
(-5675 1850);
DISPLAY 1.446809 (-5675 1850);
PAINT GREEN (-5675 1850);
DISPLAY INVISIBLE (-5675 1850);
FORCEPROP 1 LAST PATH I14
J 2
(-5348 1975);
DISPLAY 0.872340 (-5348 1975);
PAINT GREEN (-5348 1975);
DISPLAY INVISIBLE (-5348 1975);
FORCEADD TAP..1
R 2
(-5350 2025);
FORCEPROP 3 LASTPIN (-5300 2025) SIG_NAME TP_P3E_CPU1_PE1_MP_RXP<3>
J 0
(-5290 2035);
DISPLAY 0.659574 (-5290 2035);
PAINT MONO (-5290 2035);
DISPLAY INVISIBLE (-5290 2035);
FORCEPROP 1 LASTPIN (-5300 2025) BN 3
J 2
(-5288 2033);
DISPLAY 0.617021 (-5288 2033);
PAINT GREEN (-5288 2033);
FORCEPROP 2 LAST CDS_LIB mstr_standard
J 0
(-5350 2025);
PAINT MONO (-5350 2025);
DISPLAY INVISIBLE (-5350 2025);
FORCEPROP 1 LAST BODY_TYPE PLUMBING
J 2
(-5350 2075);
DISPLAY 1.446809 (-5350 2075);
PAINT GREEN (-5350 2075);
DISPLAY INVISIBLE (-5350 2075);
FORCEPROP 1 LAST HDL_TAP TRUE
J 2
(-5675 1900);
DISPLAY 1.446809 (-5675 1900);
PAINT GREEN (-5675 1900);
DISPLAY INVISIBLE (-5675 1900);
FORCEPROP 1 LAST PATH I15
J 2
(-5348 2025);
DISPLAY 0.872340 (-5348 2025);
PAINT GREEN (-5348 2025);
DISPLAY INVISIBLE (-5348 2025);
FORCEADD TAP..1
R 2
(-5350 2425);
FORCEPROP 3 LASTPIN (-5300 2425) SIG_NAME TP_P3E_CPU1_PE1_MP_RXP<5>
J 0
(-5290 2435);
DISPLAY 0.659574 (-5290 2435);
PAINT MONO (-5290 2435);
DISPLAY INVISIBLE (-5290 2435);
FORCEPROP 1 LASTPIN (-5300 2425) BN 5
J 2
(-5288 2433);
DISPLAY 0.617021 (-5288 2433);
PAINT GREEN (-5288 2433);
FORCEPROP 2 LAST CDS_LIB mstr_standard
J 0
(-5350 2425);
PAINT MONO (-5350 2425);
DISPLAY INVISIBLE (-5350 2425);
FORCEPROP 1 LAST BODY_TYPE PLUMBING
J 2
(-5350 2475);
DISPLAY 1.446809 (-5350 2475);
PAINT GREEN (-5350 2475);
DISPLAY INVISIBLE (-5350 2475);
FORCEPROP 1 LAST HDL_TAP TRUE
J 2
(-5675 2300);
DISPLAY 1.446809 (-5675 2300);
PAINT GREEN (-5675 2300);
DISPLAY INVISIBLE (-5675 2300);
FORCEPROP 1 LAST PATH I16
J 2
(-5348 2425);
DISPLAY 0.872340 (-5348 2425);
PAINT GREEN (-5348 2425);
DISPLAY INVISIBLE (-5348 2425);
FORCEADD TAP..1
R 2
(-5350 2375);
FORCEPROP 3 LASTPIN (-5300 2375) SIG_NAME TP_P3E_CPU1_PE1_MP_RXP<4>
J 0
(-5290 2385);
DISPLAY 0.659574 (-5290 2385);
PAINT MONO (-5290 2385);
DISPLAY INVISIBLE (-5290 2385);
FORCEPROP 1 LASTPIN (-5300 2375) BN 4
J 2
(-5288 2383);
DISPLAY 0.617021 (-5288 2383);
PAINT GREEN (-5288 2383);
FORCEPROP 2 LAST CDS_LIB mstr_standard
J 0
(-5350 2375);
PAINT MONO (-5350 2375);
DISPLAY INVISIBLE (-5350 2375);
FORCEPROP 1 LAST BODY_TYPE PLUMBING
J 2
(-5350 2425);
DISPLAY 1.446809 (-5350 2425);
PAINT GREEN (-5350 2425);
DISPLAY INVISIBLE (-5350 2425);
FORCEPROP 1 LAST HDL_TAP TRUE
J 2
(-5675 2250);
DISPLAY 1.446809 (-5675 2250);
PAINT GREEN (-5675 2250);
DISPLAY INVISIBLE (-5675 2250);
FORCEPROP 1 LAST PATH I17
J 2
(-5348 2375);
DISPLAY 0.872340 (-5348 2375);
PAINT GREEN (-5348 2375);
DISPLAY INVISIBLE (-5348 2375);
FORCEADD TAP..1
R 2
(-5350 2475);
FORCEPROP 3 LASTPIN (-5300 2475) SIG_NAME TP_P3E_CPU1_PE1_MP_RXP<6>
J 0
(-5290 2485);
DISPLAY 0.659574 (-5290 2485);
PAINT MONO (-5290 2485);
DISPLAY INVISIBLE (-5290 2485);
FORCEPROP 1 LASTPIN (-5300 2475) BN 6
J 2
(-5288 2483);
DISPLAY 0.617021 (-5288 2483);
PAINT GREEN (-5288 2483);
FORCEPROP 2 LAST CDS_LIB mstr_standard
J 0
(-5350 2475);
PAINT MONO (-5350 2475);
DISPLAY INVISIBLE (-5350 2475);
FORCEPROP 1 LAST BODY_TYPE PLUMBING
J 2
(-5350 2525);
DISPLAY 1.446809 (-5350 2525);
PAINT GREEN (-5350 2525);
DISPLAY INVISIBLE (-5350 2525);
FORCEPROP 1 LAST HDL_TAP TRUE
J 2
(-5675 2350);
DISPLAY 1.446809 (-5675 2350);
PAINT GREEN (-5675 2350);
DISPLAY INVISIBLE (-5675 2350);
FORCEPROP 1 LAST PATH I18
J 2
(-5348 2475);
DISPLAY 0.872340 (-5348 2475);
PAINT GREEN (-5348 2475);
DISPLAY INVISIBLE (-5348 2475);
FORCEADD TAP..1
R 2
(-5500 2625);
FORCEPROP 3 LASTPIN (-5450 2625) SIG_NAME TP_P3E_CPU1_PE1_RSR3_RXN<8>
J 0
(-5440 2635);
DISPLAY 0.659574 (-5440 2635);
PAINT MONO (-5440 2635);
DISPLAY INVISIBLE (-5440 2635);
FORCEPROP 1 LASTPIN (-5450 2625) BN 8
J 2
(-5438 2633);
DISPLAY 0.617021 (-5438 2633);
PAINT GREEN (-5438 2633);
FORCEPROP 2 LAST CDS_LIB mstr_standard
J 0
(-5500 2625);
PAINT MONO (-5500 2625);
DISPLAY INVISIBLE (-5500 2625);
FORCEPROP 1 LAST BODY_TYPE PLUMBING
J 2
(-5500 2675);
DISPLAY 1.446809 (-5500 2675);
PAINT GREEN (-5500 2675);
DISPLAY INVISIBLE (-5500 2675);
FORCEPROP 1 LAST HDL_TAP TRUE
J 2
(-5825 2500);
DISPLAY 1.446809 (-5825 2500);
PAINT GREEN (-5825 2500);
DISPLAY INVISIBLE (-5825 2500);
FORCEPROP 1 LAST PATH I19
J 2
(-5498 2625);
DISPLAY 0.872340 (-5498 2625);
PAINT GREEN (-5498 2625);
DISPLAY INVISIBLE (-5498 2625);
FORCEADD TAP..1
R 2
(-5500 2675);
FORCEPROP 3 LASTPIN (-5450 2675) SIG_NAME TP_P3E_CPU1_PE1_RSR3_RXN<9>
J 0
(-5440 2685);
DISPLAY 0.659574 (-5440 2685);
PAINT MONO (-5440 2685);
DISPLAY INVISIBLE (-5440 2685);
FORCEPROP 1 LASTPIN (-5450 2675) BN 9
J 2
(-5438 2683);
DISPLAY 0.617021 (-5438 2683);
PAINT GREEN (-5438 2683);
FORCEPROP 2 LAST CDS_LIB mstr_standard
J 0
(-5500 2675);
PAINT MONO (-5500 2675);
DISPLAY INVISIBLE (-5500 2675);
FORCEPROP 1 LAST BODY_TYPE PLUMBING
J 2
(-5500 2725);
DISPLAY 1.446809 (-5500 2725);
PAINT GREEN (-5500 2725);
DISPLAY INVISIBLE (-5500 2725);
FORCEPROP 1 LAST HDL_TAP TRUE
J 2
(-5825 2550);
DISPLAY 1.446809 (-5825 2550);
PAINT GREEN (-5825 2550);
DISPLAY INVISIBLE (-5825 2550);
FORCEPROP 1 LAST PATH I20
J 2
(-5498 2675);
DISPLAY 0.872340 (-5498 2675);
PAINT GREEN (-5498 2675);
DISPLAY INVISIBLE (-5498 2675);
FORCEADD TAP..1
R 2
(-5500 2725);
FORCEPROP 3 LASTPIN (-5450 2725) SIG_NAME TP_P3E_CPU1_PE1_RSR3_RXN<10>
J 0
(-5440 2735);
DISPLAY 0.659574 (-5440 2735);
PAINT MONO (-5440 2735);
DISPLAY INVISIBLE (-5440 2735);
FORCEPROP 1 LASTPIN (-5450 2725) BN 10
J 2
(-5438 2733);
DISPLAY 0.617021 (-5438 2733);
PAINT GREEN (-5438 2733);
FORCEPROP 2 LAST CDS_LIB mstr_standard
J 0
(-5500 2725);
PAINT MONO (-5500 2725);
DISPLAY INVISIBLE (-5500 2725);
FORCEPROP 1 LAST BODY_TYPE PLUMBING
J 2
(-5500 2775);
DISPLAY 1.446809 (-5500 2775);
PAINT GREEN (-5500 2775);
DISPLAY INVISIBLE (-5500 2775);
FORCEPROP 1 LAST HDL_TAP TRUE
J 2
(-5825 2600);
DISPLAY 1.446809 (-5825 2600);
PAINT GREEN (-5825 2600);
DISPLAY INVISIBLE (-5825 2600);
FORCEPROP 1 LAST PATH I21
J 2
(-5498 2725);
DISPLAY 0.872340 (-5498 2725);
PAINT GREEN (-5498 2725);
DISPLAY INVISIBLE (-5498 2725);
FORCEADD TAP..1
R 2
(-5500 2775);
FORCEPROP 3 LASTPIN (-5450 2775) SIG_NAME TP_P3E_CPU1_PE1_RSR3_RXN<11>
J 0
(-5440 2785);
DISPLAY 0.659574 (-5440 2785);
PAINT MONO (-5440 2785);
DISPLAY INVISIBLE (-5440 2785);
FORCEPROP 1 LASTPIN (-5450 2775) BN 11
J 2
(-5438 2783);
DISPLAY 0.617021 (-5438 2783);
PAINT GREEN (-5438 2783);
FORCEPROP 2 LAST CDS_LIB mstr_standard
J 0
(-5500 2775);
PAINT MONO (-5500 2775);
DISPLAY INVISIBLE (-5500 2775);
FORCEPROP 1 LAST BODY_TYPE PLUMBING
J 2
(-5500 2825);
DISPLAY 1.446809 (-5500 2825);
PAINT GREEN (-5500 2825);
DISPLAY INVISIBLE (-5500 2825);
FORCEPROP 1 LAST HDL_TAP TRUE
J 2
(-5825 2650);
DISPLAY 1.446809 (-5825 2650);
PAINT GREEN (-5825 2650);
DISPLAY INVISIBLE (-5825 2650);
FORCEPROP 1 LAST PATH I22
J 2
(-5498 2775);
DISPLAY 0.872340 (-5498 2775);
PAINT GREEN (-5498 2775);
DISPLAY INVISIBLE (-5498 2775);
FORCEADD TAP..1
R 2
(-5350 2525);
FORCEPROP 3 LASTPIN (-5300 2525) SIG_NAME TP_P3E_CPU1_PE1_MP_RXP<7>
J 0
(-5290 2535);
DISPLAY 0.659574 (-5290 2535);
PAINT MONO (-5290 2535);
DISPLAY INVISIBLE (-5290 2535);
FORCEPROP 1 LASTPIN (-5300 2525) BN 7
J 2
(-5288 2533);
DISPLAY 0.617021 (-5288 2533);
PAINT GREEN (-5288 2533);
FORCEPROP 2 LAST CDS_LIB mstr_standard
J 0
(-5350 2525);
PAINT MONO (-5350 2525);
DISPLAY INVISIBLE (-5350 2525);
FORCEPROP 1 LAST BODY_TYPE PLUMBING
J 2
(-5350 2575);
DISPLAY 1.446809 (-5350 2575);
PAINT GREEN (-5350 2575);
DISPLAY INVISIBLE (-5350 2575);
FORCEPROP 1 LAST HDL_TAP TRUE
J 2
(-5675 2400);
DISPLAY 1.446809 (-5675 2400);
PAINT GREEN (-5675 2400);
DISPLAY INVISIBLE (-5675 2400);
FORCEPROP 1 LAST PATH I23
J 2
(-5348 2525);
DISPLAY 0.872340 (-5348 2525);
PAINT GREEN (-5348 2525);
DISPLAY INVISIBLE (-5348 2525);
FORCEADD TAP..1
R 2
(-5350 2875);
FORCEPROP 3 LASTPIN (-5300 2875) SIG_NAME TP_P3E_CPU1_PE1_RSR3_RXP<8>
J 0
(-5290 2885);
DISPLAY 0.659574 (-5290 2885);
PAINT MONO (-5290 2885);
DISPLAY INVISIBLE (-5290 2885);
FORCEPROP 1 LASTPIN (-5300 2875) BN 8
J 2
(-5288 2883);
DISPLAY 0.617021 (-5288 2883);
PAINT GREEN (-5288 2883);
FORCEPROP 2 LAST CDS_LIB mstr_standard
J 0
(-5350 2875);
PAINT MONO (-5350 2875);
DISPLAY INVISIBLE (-5350 2875);
FORCEPROP 1 LAST BODY_TYPE PLUMBING
J 2
(-5350 2925);
DISPLAY 1.446809 (-5350 2925);
PAINT GREEN (-5350 2925);
DISPLAY INVISIBLE (-5350 2925);
FORCEPROP 1 LAST HDL_TAP TRUE
J 2
(-5675 2750);
DISPLAY 1.446809 (-5675 2750);
PAINT GREEN (-5675 2750);
DISPLAY INVISIBLE (-5675 2750);
FORCEPROP 1 LAST PATH I24
J 2
(-5348 2875);
DISPLAY 0.872340 (-5348 2875);
PAINT GREEN (-5348 2875);
DISPLAY INVISIBLE (-5348 2875);
FORCEADD TAP..1
R 2
(-5350 2925);
FORCEPROP 3 LASTPIN (-5300 2925) SIG_NAME TP_P3E_CPU1_PE1_RSR3_RXP<9>
J 0
(-5290 2935);
DISPLAY 0.659574 (-5290 2935);
PAINT MONO (-5290 2935);
DISPLAY INVISIBLE (-5290 2935);
FORCEPROP 1 LASTPIN (-5300 2925) BN 9
J 2
(-5288 2933);
DISPLAY 0.617021 (-5288 2933);
PAINT GREEN (-5288 2933);
FORCEPROP 2 LAST CDS_LIB mstr_standard
J 0
(-5350 2925);
PAINT MONO (-5350 2925);
DISPLAY INVISIBLE (-5350 2925);
FORCEPROP 1 LAST BODY_TYPE PLUMBING
J 2
(-5350 2975);
DISPLAY 1.446809 (-5350 2975);
PAINT GREEN (-5350 2975);
DISPLAY INVISIBLE (-5350 2975);
FORCEPROP 1 LAST HDL_TAP TRUE
J 2
(-5675 2800);
DISPLAY 1.446809 (-5675 2800);
PAINT GREEN (-5675 2800);
DISPLAY INVISIBLE (-5675 2800);
FORCEPROP 1 LAST PATH I25
J 2
(-5348 2925);
DISPLAY 0.872340 (-5348 2925);
PAINT GREEN (-5348 2925);
DISPLAY INVISIBLE (-5348 2925);
FORCEADD TAP..1
R 2
(-5350 2975);
FORCEPROP 3 LASTPIN (-5300 2975) SIG_NAME TP_P3E_CPU1_PE1_RSR3_RXP<10>
J 0
(-5290 2985);
DISPLAY 0.659574 (-5290 2985);
PAINT MONO (-5290 2985);
DISPLAY INVISIBLE (-5290 2985);
FORCEPROP 1 LASTPIN (-5300 2975) BN 10
J 2
(-5288 2983);
DISPLAY 0.617021 (-5288 2983);
PAINT GREEN (-5288 2983);
FORCEPROP 2 LAST CDS_LIB mstr_standard
J 0
(-5350 2975);
PAINT MONO (-5350 2975);
DISPLAY INVISIBLE (-5350 2975);
FORCEPROP 1 LAST BODY_TYPE PLUMBING
J 2
(-5350 3025);
DISPLAY 1.446809 (-5350 3025);
PAINT GREEN (-5350 3025);
DISPLAY INVISIBLE (-5350 3025);
FORCEPROP 1 LAST HDL_TAP TRUE
J 2
(-5675 2850);
DISPLAY 1.446809 (-5675 2850);
PAINT GREEN (-5675 2850);
DISPLAY INVISIBLE (-5675 2850);
FORCEPROP 1 LAST PATH I26
J 2
(-5348 2975);
DISPLAY 0.872340 (-5348 2975);
PAINT GREEN (-5348 2975);
DISPLAY INVISIBLE (-5348 2975);
FORCEADD TAP..1
R 2
(-5500 3225);
FORCEPROP 3 LASTPIN (-5450 3225) SIG_NAME TP_P3E_CPU1_PE1_RSR3_RXN<14>
J 0
(-5440 3235);
DISPLAY 0.659574 (-5440 3235);
PAINT MONO (-5440 3235);
DISPLAY INVISIBLE (-5440 3235);
FORCEPROP 1 LASTPIN (-5450 3225) BN 14
J 2
(-5438 3233);
DISPLAY 0.617021 (-5438 3233);
PAINT GREEN (-5438 3233);
FORCEPROP 2 LAST CDS_LIB mstr_standard
J 0
(-5500 3225);
PAINT MONO (-5500 3225);
DISPLAY INVISIBLE (-5500 3225);
FORCEPROP 1 LAST BODY_TYPE PLUMBING
J 2
(-5500 3275);
DISPLAY 1.446809 (-5500 3275);
PAINT GREEN (-5500 3275);
DISPLAY INVISIBLE (-5500 3275);
FORCEPROP 1 LAST HDL_TAP TRUE
J 2
(-5825 3100);
DISPLAY 1.446809 (-5825 3100);
PAINT GREEN (-5825 3100);
DISPLAY INVISIBLE (-5825 3100);
FORCEPROP 1 LAST PATH I27
J 2
(-5498 3225);
DISPLAY 0.872340 (-5498 3225);
PAINT GREEN (-5498 3225);
DISPLAY INVISIBLE (-5498 3225);
FORCEADD TAP..1
R 2
(-5500 3175);
FORCEPROP 3 LASTPIN (-5450 3175) SIG_NAME TP_P3E_CPU1_PE1_RSR3_RXN<13>
J 0
(-5440 3185);
DISPLAY 0.659574 (-5440 3185);
PAINT MONO (-5440 3185);
DISPLAY INVISIBLE (-5440 3185);
FORCEPROP 1 LASTPIN (-5450 3175) BN 13
J 2
(-5438 3183);
DISPLAY 0.617021 (-5438 3183);
PAINT GREEN (-5438 3183);
FORCEPROP 2 LAST CDS_LIB mstr_standard
J 0
(-5500 3175);
PAINT MONO (-5500 3175);
DISPLAY INVISIBLE (-5500 3175);
FORCEPROP 1 LAST BODY_TYPE PLUMBING
J 2
(-5500 3225);
DISPLAY 1.446809 (-5500 3225);
PAINT GREEN (-5500 3225);
DISPLAY INVISIBLE (-5500 3225);
FORCEPROP 1 LAST HDL_TAP TRUE
J 2
(-5825 3050);
DISPLAY 1.446809 (-5825 3050);
PAINT GREEN (-5825 3050);
DISPLAY INVISIBLE (-5825 3050);
FORCEPROP 1 LAST PATH I28
J 2
(-5498 3175);
DISPLAY 0.872340 (-5498 3175);
PAINT GREEN (-5498 3175);
DISPLAY INVISIBLE (-5498 3175);
FORCEADD TAP..1
R 2
(-5500 3125);
FORCEPROP 3 LASTPIN (-5450 3125) SIG_NAME TP_P3E_CPU1_PE1_RSR3_RXN<12>
J 0
(-5440 3135);
DISPLAY 0.659574 (-5440 3135);
PAINT MONO (-5440 3135);
DISPLAY INVISIBLE (-5440 3135);
FORCEPROP 1 LASTPIN (-5450 3125) BN 12
J 2
(-5438 3133);
DISPLAY 0.617021 (-5438 3133);
PAINT GREEN (-5438 3133);
FORCEPROP 2 LAST CDS_LIB mstr_standard
J 0
(-5500 3125);
PAINT MONO (-5500 3125);
DISPLAY INVISIBLE (-5500 3125);
FORCEPROP 1 LAST BODY_TYPE PLUMBING
J 2
(-5500 3175);
DISPLAY 1.446809 (-5500 3175);
PAINT GREEN (-5500 3175);
DISPLAY INVISIBLE (-5500 3175);
FORCEPROP 1 LAST HDL_TAP TRUE
J 2
(-5825 3000);
DISPLAY 1.446809 (-5825 3000);
PAINT GREEN (-5825 3000);
DISPLAY INVISIBLE (-5825 3000);
FORCEPROP 1 LAST PATH I29
J 2
(-5498 3125);
DISPLAY 0.872340 (-5498 3125);
PAINT GREEN (-5498 3125);
DISPLAY INVISIBLE (-5498 3125);
FORCEADD TAP..1
R 2
(-5500 1625);
FORCEPROP 3 LASTPIN (-5450 1625) SIG_NAME TP_P3E_CPU1_PE1_MP_RXN<0>
J 0
(-5440 1635);
DISPLAY 0.659574 (-5440 1635);
PAINT MONO (-5440 1635);
DISPLAY INVISIBLE (-5440 1635);
FORCEPROP 1 LASTPIN (-5450 1625) BN 0
J 2
(-5438 1633);
DISPLAY 0.617021 (-5438 1633);
PAINT GREEN (-5438 1633);
FORCEPROP 2 LAST CDS_LIB mstr_standard
J 0
(-5500 1625);
PAINT MONO (-5500 1625);
DISPLAY INVISIBLE (-5500 1625);
FORCEPROP 1 LAST BODY_TYPE PLUMBING
J 2
(-5500 1675);
DISPLAY 1.446809 (-5500 1675);
PAINT GREEN (-5500 1675);
DISPLAY INVISIBLE (-5500 1675);
FORCEPROP 1 LAST HDL_TAP TRUE
J 2
(-5825 1500);
DISPLAY 1.446809 (-5825 1500);
PAINT GREEN (-5825 1500);
DISPLAY INVISIBLE (-5825 1500);
FORCEPROP 1 LAST PATH I3
J 2
(-5498 1625);
DISPLAY 0.872340 (-5498 1625);
PAINT GREEN (-5498 1625);
DISPLAY INVISIBLE (-5498 1625);
FORCEADD TAP..1
R 2
(-5500 3275);
FORCEPROP 3 LASTPIN (-5450 3275) SIG_NAME TP_P3E_CPU1_PE1_RSR3_RXN<15>
J 0
(-5440 3285);
DISPLAY 0.659574 (-5440 3285);
PAINT MONO (-5440 3285);
DISPLAY INVISIBLE (-5440 3285);
FORCEPROP 1 LASTPIN (-5450 3275) BN 15
J 2
(-5438 3283);
DISPLAY 0.617021 (-5438 3283);
PAINT GREEN (-5438 3283);
FORCEPROP 2 LAST CDS_LIB mstr_standard
J 0
(-5500 3275);
PAINT MONO (-5500 3275);
DISPLAY INVISIBLE (-5500 3275);
FORCEPROP 1 LAST BODY_TYPE PLUMBING
J 2
(-5500 3325);
DISPLAY 1.446809 (-5500 3325);
PAINT GREEN (-5500 3325);
DISPLAY INVISIBLE (-5500 3325);
FORCEPROP 1 LAST HDL_TAP TRUE
J 2
(-5825 3150);
DISPLAY 1.446809 (-5825 3150);
PAINT GREEN (-5825 3150);
DISPLAY INVISIBLE (-5825 3150);
FORCEPROP 1 LAST PATH I30
J 2
(-5498 3275);
DISPLAY 0.872340 (-5498 3275);
PAINT GREEN (-5498 3275);
DISPLAY INVISIBLE (-5498 3275);
FORCEADD TAP..1
R 2
(-5350 3025);
FORCEPROP 3 LASTPIN (-5300 3025) SIG_NAME TP_P3E_CPU1_PE1_RSR3_RXP<11>
J 0
(-5290 3035);
DISPLAY 0.659574 (-5290 3035);
PAINT MONO (-5290 3035);
DISPLAY INVISIBLE (-5290 3035);
FORCEPROP 1 LASTPIN (-5300 3025) BN 11
J 2
(-5288 3033);
DISPLAY 0.617021 (-5288 3033);
PAINT GREEN (-5288 3033);
FORCEPROP 2 LAST CDS_LIB mstr_standard
J 0
(-5350 3025);
PAINT MONO (-5350 3025);
DISPLAY INVISIBLE (-5350 3025);
FORCEPROP 1 LAST BODY_TYPE PLUMBING
J 2
(-5350 3075);
DISPLAY 1.446809 (-5350 3075);
PAINT GREEN (-5350 3075);
DISPLAY INVISIBLE (-5350 3075);
FORCEPROP 1 LAST HDL_TAP TRUE
J 2
(-5675 2900);
DISPLAY 1.446809 (-5675 2900);
PAINT GREEN (-5675 2900);
DISPLAY INVISIBLE (-5675 2900);
FORCEPROP 1 LAST PATH I31
J 2
(-5348 3025);
DISPLAY 0.872340 (-5348 3025);
PAINT GREEN (-5348 3025);
DISPLAY INVISIBLE (-5348 3025);
FORCEADD TAP..1
R 2
(-5350 3375);
FORCEPROP 3 LASTPIN (-5300 3375) SIG_NAME TP_P3E_CPU1_PE1_RSR3_RXP<12>
J 0
(-5290 3385);
DISPLAY 0.659574 (-5290 3385);
PAINT MONO (-5290 3385);
DISPLAY INVISIBLE (-5290 3385);
FORCEPROP 1 LASTPIN (-5300 3375) BN 12
J 2
(-5288 3383);
DISPLAY 0.617021 (-5288 3383);
PAINT GREEN (-5288 3383);
FORCEPROP 2 LAST CDS_LIB mstr_standard
J 0
(-5350 3375);
PAINT MONO (-5350 3375);
DISPLAY INVISIBLE (-5350 3375);
FORCEPROP 1 LAST BODY_TYPE PLUMBING
J 2
(-5350 3425);
DISPLAY 1.446809 (-5350 3425);
PAINT GREEN (-5350 3425);
DISPLAY INVISIBLE (-5350 3425);
FORCEPROP 1 LAST HDL_TAP TRUE
J 2
(-5675 3250);
DISPLAY 1.446809 (-5675 3250);
PAINT GREEN (-5675 3250);
DISPLAY INVISIBLE (-5675 3250);
FORCEPROP 1 LAST PATH I32
J 2
(-5348 3375);
DISPLAY 0.872340 (-5348 3375);
PAINT GREEN (-5348 3375);
DISPLAY INVISIBLE (-5348 3375);
FORCEADD TAP..1
R 2
(-5350 3425);
FORCEPROP 3 LASTPIN (-5300 3425) SIG_NAME TP_P3E_CPU1_PE1_RSR3_RXP<13>
J 0
(-5290 3435);
DISPLAY 0.659574 (-5290 3435);
PAINT MONO (-5290 3435);
DISPLAY INVISIBLE (-5290 3435);
FORCEPROP 1 LASTPIN (-5300 3425) BN 13
J 2
(-5288 3433);
DISPLAY 0.617021 (-5288 3433);
PAINT GREEN (-5288 3433);
FORCEPROP 2 LAST CDS_LIB mstr_standard
J 0
(-5350 3425);
PAINT MONO (-5350 3425);
DISPLAY INVISIBLE (-5350 3425);
FORCEPROP 1 LAST BODY_TYPE PLUMBING
J 2
(-5350 3475);
DISPLAY 1.446809 (-5350 3475);
PAINT GREEN (-5350 3475);
DISPLAY INVISIBLE (-5350 3475);
FORCEPROP 1 LAST HDL_TAP TRUE
J 2
(-5675 3300);
DISPLAY 1.446809 (-5675 3300);
PAINT GREEN (-5675 3300);
DISPLAY INVISIBLE (-5675 3300);
FORCEPROP 1 LAST PATH I33
J 2
(-5348 3425);
DISPLAY 0.872340 (-5348 3425);
PAINT GREEN (-5348 3425);
DISPLAY INVISIBLE (-5348 3425);
FORCEADD TAP..1
R 2
(-5350 3475);
FORCEPROP 3 LASTPIN (-5300 3475) SIG_NAME TP_P3E_CPU1_PE1_RSR3_RXP<14>
J 0
(-5290 3485);
DISPLAY 0.659574 (-5290 3485);
PAINT MONO (-5290 3485);
DISPLAY INVISIBLE (-5290 3485);
FORCEPROP 1 LASTPIN (-5300 3475) BN 14
J 2
(-5288 3483);
DISPLAY 0.617021 (-5288 3483);
PAINT GREEN (-5288 3483);
FORCEPROP 2 LAST CDS_LIB mstr_standard
J 0
(-5350 3475);
PAINT MONO (-5350 3475);
DISPLAY INVISIBLE (-5350 3475);
FORCEPROP 1 LAST BODY_TYPE PLUMBING
J 2
(-5350 3525);
DISPLAY 1.446809 (-5350 3525);
PAINT GREEN (-5350 3525);
DISPLAY INVISIBLE (-5350 3525);
FORCEPROP 1 LAST HDL_TAP TRUE
J 2
(-5675 3350);
DISPLAY 1.446809 (-5675 3350);
PAINT GREEN (-5675 3350);
DISPLAY INVISIBLE (-5675 3350);
FORCEPROP 1 LAST PATH I34
J 2
(-5348 3475);
DISPLAY 0.872340 (-5348 3475);
PAINT GREEN (-5348 3475);
DISPLAY INVISIBLE (-5348 3475);
FORCEADD TAP..1
R 2
(-5350 3525);
FORCEPROP 3 LASTPIN (-5300 3525) SIG_NAME TP_P3E_CPU1_PE1_RSR3_RXP<15>
J 0
(-5290 3535);
DISPLAY 0.659574 (-5290 3535);
PAINT MONO (-5290 3535);
DISPLAY INVISIBLE (-5290 3535);
FORCEPROP 1 LASTPIN (-5300 3525) BN 15
J 2
(-5288 3533);
DISPLAY 0.617021 (-5288 3533);
PAINT GREEN (-5288 3533);
FORCEPROP 2 LAST CDS_LIB mstr_standard
J 0
(-5350 3525);
PAINT MONO (-5350 3525);
DISPLAY INVISIBLE (-5350 3525);
FORCEPROP 1 LAST BODY_TYPE PLUMBING
J 2
(-5350 3575);
DISPLAY 1.446809 (-5350 3575);
PAINT GREEN (-5350 3575);
DISPLAY INVISIBLE (-5350 3575);
FORCEPROP 1 LAST HDL_TAP TRUE
J 2
(-5675 3400);
DISPLAY 1.446809 (-5675 3400);
PAINT GREEN (-5675 3400);
DISPLAY INVISIBLE (-5675 3400);
FORCEPROP 1 LAST PATH I35
J 2
(-5348 3525);
DISPLAY 0.872340 (-5348 3525);
PAINT GREEN (-5348 3525);
DISPLAY INVISIBLE (-5348 3525);
FORCEADD TAP..1
(-2725 1625);
FORCEPROP 3 LASTPIN (-2775 1625) SIG_NAME TP_P3E_CPU1_PE1_MP_TXN<0>
J 0
(-2765 1635);
DISPLAY 0.659574 (-2765 1635);
PAINT MONO (-2765 1635);
DISPLAY INVISIBLE (-2765 1635);
FORCEPROP 1 LASTPIN (-2775 1625) BN 0
J 0
(-2787 1633);
DISPLAY 0.617021 (-2787 1633);
PAINT GREEN (-2787 1633);
FORCEPROP 2 LAST CDS_LIB mstr_standard
J 2
(-2725 1625);
PAINT MONO (-2725 1625);
DISPLAY INVISIBLE (-2725 1625);
FORCEPROP 1 LAST BODY_TYPE PLUMBING
J 0
(-2725 1675);
DISPLAY 1.446809 (-2725 1675);
PAINT GREEN (-2725 1675);
DISPLAY INVISIBLE (-2725 1675);
FORCEPROP 1 LAST HDL_TAP TRUE
J 0
(-2400 1500);
DISPLAY 1.446809 (-2400 1500);
PAINT GREEN (-2400 1500);
DISPLAY INVISIBLE (-2400 1500);
FORCEPROP 1 LAST PATH I36
J 0
(-2727 1625);
DISPLAY 0.872340 (-2727 1625);
PAINT GREEN (-2727 1625);
DISPLAY INVISIBLE (-2727 1625);
FORCEADD TAP..1
(-2725 1675);
FORCEPROP 3 LASTPIN (-2775 1675) SIG_NAME TP_P3E_CPU1_PE1_MP_TXN<1>
J 0
(-2765 1685);
DISPLAY 0.659574 (-2765 1685);
PAINT MONO (-2765 1685);
DISPLAY INVISIBLE (-2765 1685);
FORCEPROP 1 LASTPIN (-2775 1675) BN 1
J 0
(-2787 1683);
DISPLAY 0.617021 (-2787 1683);
PAINT GREEN (-2787 1683);
FORCEPROP 2 LAST CDS_LIB mstr_standard
J 2
(-2725 1675);
PAINT MONO (-2725 1675);
DISPLAY INVISIBLE (-2725 1675);
FORCEPROP 1 LAST BODY_TYPE PLUMBING
J 0
(-2725 1725);
DISPLAY 1.446809 (-2725 1725);
PAINT GREEN (-2725 1725);
DISPLAY INVISIBLE (-2725 1725);
FORCEPROP 1 LAST HDL_TAP TRUE
J 0
(-2400 1550);
DISPLAY 1.446809 (-2400 1550);
PAINT GREEN (-2400 1550);
DISPLAY INVISIBLE (-2400 1550);
FORCEPROP 1 LAST PATH I37
J 0
(-2727 1675);
DISPLAY 0.872340 (-2727 1675);
PAINT GREEN (-2727 1675);
DISPLAY INVISIBLE (-2727 1675);
FORCEADD TAP..1
(-2875 1925);
FORCEPROP 3 LASTPIN (-2925 1925) SIG_NAME TP_P3E_CPU1_PE1_MP_TXP<1>
J 0
(-2915 1935);
DISPLAY 0.659574 (-2915 1935);
PAINT MONO (-2915 1935);
DISPLAY INVISIBLE (-2915 1935);
FORCEPROP 1 LASTPIN (-2925 1925) BN 1
J 0
(-2937 1933);
DISPLAY 0.617021 (-2937 1933);
PAINT GREEN (-2937 1933);
FORCEPROP 2 LAST CDS_LIB mstr_standard
J 2
(-2875 1925);
PAINT MONO (-2875 1925);
DISPLAY INVISIBLE (-2875 1925);
FORCEPROP 1 LAST BODY_TYPE PLUMBING
J 0
(-2875 1975);
DISPLAY 1.446809 (-2875 1975);
PAINT GREEN (-2875 1975);
DISPLAY INVISIBLE (-2875 1975);
FORCEPROP 1 LAST HDL_TAP TRUE
J 0
(-2550 1800);
DISPLAY 1.446809 (-2550 1800);
PAINT GREEN (-2550 1800);
DISPLAY INVISIBLE (-2550 1800);
FORCEPROP 1 LAST PATH I38
J 0
(-2877 1925);
DISPLAY 0.872340 (-2877 1925);
PAINT GREEN (-2877 1925);
DISPLAY INVISIBLE (-2877 1925);
FORCEADD TAP..1
(-2875 1875);
FORCEPROP 3 LASTPIN (-2925 1875) SIG_NAME TP_P3E_CPU1_PE1_MP_TXP<0>
J 0
(-2915 1885);
DISPLAY 0.659574 (-2915 1885);
PAINT MONO (-2915 1885);
DISPLAY INVISIBLE (-2915 1885);
FORCEPROP 1 LASTPIN (-2925 1875) BN 0
J 0
(-2937 1883);
DISPLAY 0.617021 (-2937 1883);
PAINT GREEN (-2937 1883);
FORCEPROP 2 LAST CDS_LIB mstr_standard
J 2
(-2875 1875);
PAINT MONO (-2875 1875);
DISPLAY INVISIBLE (-2875 1875);
FORCEPROP 1 LAST BODY_TYPE PLUMBING
J 0
(-2875 1925);
DISPLAY 1.446809 (-2875 1925);
PAINT GREEN (-2875 1925);
DISPLAY INVISIBLE (-2875 1925);
FORCEPROP 1 LAST HDL_TAP TRUE
J 0
(-2550 1750);
DISPLAY 1.446809 (-2550 1750);
PAINT GREEN (-2550 1750);
DISPLAY INVISIBLE (-2550 1750);
FORCEPROP 1 LAST PATH I39
J 0
(-2877 1875);
DISPLAY 0.872340 (-2877 1875);
PAINT GREEN (-2877 1875);
DISPLAY INVISIBLE (-2877 1875);
FORCEADD TAP..1
R 2
(-5500 1675);
FORCEPROP 3 LASTPIN (-5450 1675) SIG_NAME TP_P3E_CPU1_PE1_MP_RXN<1>
J 0
(-5440 1685);
DISPLAY 0.659574 (-5440 1685);
PAINT MONO (-5440 1685);
DISPLAY INVISIBLE (-5440 1685);
FORCEPROP 1 LASTPIN (-5450 1675) BN 1
J 2
(-5438 1683);
DISPLAY 0.617021 (-5438 1683);
PAINT GREEN (-5438 1683);
FORCEPROP 2 LAST CDS_LIB mstr_standard
J 0
(-5500 1675);
PAINT MONO (-5500 1675);
DISPLAY INVISIBLE (-5500 1675);
FORCEPROP 1 LAST BODY_TYPE PLUMBING
J 2
(-5500 1725);
DISPLAY 1.446809 (-5500 1725);
PAINT GREEN (-5500 1725);
DISPLAY INVISIBLE (-5500 1725);
FORCEPROP 1 LAST HDL_TAP TRUE
J 2
(-5825 1550);
DISPLAY 1.446809 (-5825 1550);
PAINT GREEN (-5825 1550);
DISPLAY INVISIBLE (-5825 1550);
FORCEPROP 1 LAST PATH I4
J 2
(-5498 1675);
DISPLAY 0.872340 (-5498 1675);
PAINT GREEN (-5498 1675);
DISPLAY INVISIBLE (-5498 1675);
FORCEADD TAP..1
(-2725 1775);
FORCEPROP 3 LASTPIN (-2775 1775) SIG_NAME TP_P3E_CPU1_PE1_MP_TXN<3>
J 0
(-2765 1785);
DISPLAY 0.659574 (-2765 1785);
PAINT MONO (-2765 1785);
DISPLAY INVISIBLE (-2765 1785);
FORCEPROP 1 LASTPIN (-2775 1775) BN 3
J 0
(-2787 1783);
DISPLAY 0.617021 (-2787 1783);
PAINT GREEN (-2787 1783);
FORCEPROP 2 LAST CDS_LIB mstr_standard
J 2
(-2725 1775);
PAINT MONO (-2725 1775);
DISPLAY INVISIBLE (-2725 1775);
FORCEPROP 1 LAST BODY_TYPE PLUMBING
J 0
(-2725 1825);
DISPLAY 1.446809 (-2725 1825);
PAINT GREEN (-2725 1825);
DISPLAY INVISIBLE (-2725 1825);
FORCEPROP 1 LAST HDL_TAP TRUE
J 0
(-2400 1650);
DISPLAY 1.446809 (-2400 1650);
PAINT GREEN (-2400 1650);
DISPLAY INVISIBLE (-2400 1650);
FORCEPROP 1 LAST PATH I40
J 0
(-2727 1775);
DISPLAY 0.872340 (-2727 1775);
PAINT GREEN (-2727 1775);
DISPLAY INVISIBLE (-2727 1775);
FORCEADD TAP..1
(-2725 1725);
FORCEPROP 3 LASTPIN (-2775 1725) SIG_NAME TP_P3E_CPU1_PE1_MP_TXN<2>
J 0
(-2765 1735);
DISPLAY 0.659574 (-2765 1735);
PAINT MONO (-2765 1735);
DISPLAY INVISIBLE (-2765 1735);
FORCEPROP 1 LASTPIN (-2775 1725) BN 2
J 0
(-2787 1733);
DISPLAY 0.617021 (-2787 1733);
PAINT GREEN (-2787 1733);
FORCEPROP 2 LAST CDS_LIB mstr_standard
J 2
(-2725 1725);
PAINT MONO (-2725 1725);
DISPLAY INVISIBLE (-2725 1725);
FORCEPROP 1 LAST BODY_TYPE PLUMBING
J 0
(-2725 1775);
DISPLAY 1.446809 (-2725 1775);
PAINT GREEN (-2725 1775);
DISPLAY INVISIBLE (-2725 1775);
FORCEPROP 1 LAST HDL_TAP TRUE
J 0
(-2400 1600);
DISPLAY 1.446809 (-2400 1600);
PAINT GREEN (-2400 1600);
DISPLAY INVISIBLE (-2400 1600);
FORCEPROP 1 LAST PATH I41
J 0
(-2727 1725);
DISPLAY 0.872340 (-2727 1725);
PAINT GREEN (-2727 1725);
DISPLAY INVISIBLE (-2727 1725);
FORCEADD TAP..1
(-2875 2025);
FORCEPROP 3 LASTPIN (-2925 2025) SIG_NAME TP_P3E_CPU1_PE1_MP_TXP<3>
J 0
(-2915 2035);
DISPLAY 0.659574 (-2915 2035);
PAINT MONO (-2915 2035);
DISPLAY INVISIBLE (-2915 2035);
FORCEPROP 1 LASTPIN (-2925 2025) BN 3
J 0
(-2937 2033);
DISPLAY 0.617021 (-2937 2033);
PAINT GREEN (-2937 2033);
FORCEPROP 2 LAST CDS_LIB mstr_standard
J 2
(-2875 2025);
PAINT MONO (-2875 2025);
DISPLAY INVISIBLE (-2875 2025);
FORCEPROP 1 LAST BODY_TYPE PLUMBING
J 0
(-2875 2075);
DISPLAY 1.446809 (-2875 2075);
PAINT GREEN (-2875 2075);
DISPLAY INVISIBLE (-2875 2075);
FORCEPROP 1 LAST HDL_TAP TRUE
J 0
(-2550 1900);
DISPLAY 1.446809 (-2550 1900);
PAINT GREEN (-2550 1900);
DISPLAY INVISIBLE (-2550 1900);
FORCEPROP 1 LAST PATH I42
J 0
(-2877 2025);
DISPLAY 0.872340 (-2877 2025);
PAINT GREEN (-2877 2025);
DISPLAY INVISIBLE (-2877 2025);
FORCEADD TAP..1
(-2875 1975);
FORCEPROP 3 LASTPIN (-2925 1975) SIG_NAME TP_P3E_CPU1_PE1_MP_TXP<2>
J 0
(-2915 1985);
DISPLAY 0.659574 (-2915 1985);
PAINT MONO (-2915 1985);
DISPLAY INVISIBLE (-2915 1985);
FORCEPROP 1 LASTPIN (-2925 1975) BN 2
J 0
(-2937 1983);
DISPLAY 0.617021 (-2937 1983);
PAINT GREEN (-2937 1983);
FORCEPROP 2 LAST CDS_LIB mstr_standard
J 2
(-2875 1975);
PAINT MONO (-2875 1975);
DISPLAY INVISIBLE (-2875 1975);
FORCEPROP 1 LAST BODY_TYPE PLUMBING
J 0
(-2875 2025);
DISPLAY 1.446809 (-2875 2025);
PAINT GREEN (-2875 2025);
DISPLAY INVISIBLE (-2875 2025);
FORCEPROP 1 LAST HDL_TAP TRUE
J 0
(-2550 1850);
DISPLAY 1.446809 (-2550 1850);
PAINT GREEN (-2550 1850);
DISPLAY INVISIBLE (-2550 1850);
FORCEPROP 1 LAST PATH I43
J 0
(-2877 1975);
DISPLAY 0.872340 (-2877 1975);
PAINT GREEN (-2877 1975);
DISPLAY INVISIBLE (-2877 1975);
FORCEADD TAP..1
(-2725 2125);
FORCEPROP 3 LASTPIN (-2775 2125) SIG_NAME TP_P3E_CPU1_PE1_MP_TXN<4>
J 0
(-2765 2135);
DISPLAY 0.659574 (-2765 2135);
PAINT MONO (-2765 2135);
DISPLAY INVISIBLE (-2765 2135);
FORCEPROP 1 LASTPIN (-2775 2125) BN 4
J 0
(-2787 2133);
DISPLAY 0.617021 (-2787 2133);
PAINT GREEN (-2787 2133);
FORCEPROP 2 LAST CDS_LIB mstr_standard
J 2
(-2725 2125);
PAINT MONO (-2725 2125);
DISPLAY INVISIBLE (-2725 2125);
FORCEPROP 1 LAST BODY_TYPE PLUMBING
J 0
(-2725 2175);
DISPLAY 1.446809 (-2725 2175);
PAINT GREEN (-2725 2175);
DISPLAY INVISIBLE (-2725 2175);
FORCEPROP 1 LAST HDL_TAP TRUE
J 0
(-2400 2000);
DISPLAY 1.446809 (-2400 2000);
PAINT GREEN (-2400 2000);
DISPLAY INVISIBLE (-2400 2000);
FORCEPROP 1 LAST PATH I44
J 0
(-2727 2125);
DISPLAY 0.872340 (-2727 2125);
PAINT GREEN (-2727 2125);
DISPLAY INVISIBLE (-2727 2125);
FORCEADD TAP..1
(-2725 2175);
FORCEPROP 3 LASTPIN (-2775 2175) SIG_NAME TP_P3E_CPU1_PE1_MP_TXN<5>
J 0
(-2765 2185);
DISPLAY 0.659574 (-2765 2185);
PAINT MONO (-2765 2185);
DISPLAY INVISIBLE (-2765 2185);
FORCEPROP 1 LASTPIN (-2775 2175) BN 5
J 0
(-2787 2183);
DISPLAY 0.617021 (-2787 2183);
PAINT GREEN (-2787 2183);
FORCEPROP 2 LAST CDS_LIB mstr_standard
J 2
(-2725 2175);
PAINT MONO (-2725 2175);
DISPLAY INVISIBLE (-2725 2175);
FORCEPROP 1 LAST BODY_TYPE PLUMBING
J 0
(-2725 2225);
DISPLAY 1.446809 (-2725 2225);
PAINT GREEN (-2725 2225);
DISPLAY INVISIBLE (-2725 2225);
FORCEPROP 1 LAST HDL_TAP TRUE
J 0
(-2400 2050);
DISPLAY 1.446809 (-2400 2050);
PAINT GREEN (-2400 2050);
DISPLAY INVISIBLE (-2400 2050);
FORCEPROP 1 LAST PATH I45
J 0
(-2727 2175);
DISPLAY 0.872340 (-2727 2175);
PAINT GREEN (-2727 2175);
DISPLAY INVISIBLE (-2727 2175);
FORCEADD TAP..1
(-2725 2225);
FORCEPROP 3 LASTPIN (-2775 2225) SIG_NAME TP_P3E_CPU1_PE1_MP_TXN<6>
J 0
(-2765 2235);
DISPLAY 0.659574 (-2765 2235);
PAINT MONO (-2765 2235);
DISPLAY INVISIBLE (-2765 2235);
FORCEPROP 1 LASTPIN (-2775 2225) BN 6
J 0
(-2787 2233);
DISPLAY 0.617021 (-2787 2233);
PAINT GREEN (-2787 2233);
FORCEPROP 2 LAST CDS_LIB mstr_standard
J 2
(-2725 2225);
PAINT MONO (-2725 2225);
DISPLAY INVISIBLE (-2725 2225);
FORCEPROP 1 LAST BODY_TYPE PLUMBING
J 0
(-2725 2275);
DISPLAY 1.446809 (-2725 2275);
PAINT GREEN (-2725 2275);
DISPLAY INVISIBLE (-2725 2275);
FORCEPROP 1 LAST HDL_TAP TRUE
J 0
(-2400 2100);
DISPLAY 1.446809 (-2400 2100);
PAINT GREEN (-2400 2100);
DISPLAY INVISIBLE (-2400 2100);
FORCEPROP 1 LAST PATH I46
J 0
(-2727 2225);
DISPLAY 0.872340 (-2727 2225);
PAINT GREEN (-2727 2225);
DISPLAY INVISIBLE (-2727 2225);
FORCEADD TAP..1
(-2875 2375);
FORCEPROP 3 LASTPIN (-2925 2375) SIG_NAME TP_P3E_CPU1_PE1_MP_TXP<4>
J 0
(-2915 2385);
DISPLAY 0.659574 (-2915 2385);
PAINT MONO (-2915 2385);
DISPLAY INVISIBLE (-2915 2385);
FORCEPROP 1 LASTPIN (-2925 2375) BN 4
J 0
(-2937 2383);
DISPLAY 0.617021 (-2937 2383);
PAINT GREEN (-2937 2383);
FORCEPROP 2 LAST CDS_LIB mstr_standard
J 2
(-2875 2375);
PAINT MONO (-2875 2375);
DISPLAY INVISIBLE (-2875 2375);
FORCEPROP 1 LAST BODY_TYPE PLUMBING
J 0
(-2875 2425);
DISPLAY 1.446809 (-2875 2425);
PAINT GREEN (-2875 2425);
DISPLAY INVISIBLE (-2875 2425);
FORCEPROP 1 LAST HDL_TAP TRUE
J 0
(-2550 2250);
DISPLAY 1.446809 (-2550 2250);
PAINT GREEN (-2550 2250);
DISPLAY INVISIBLE (-2550 2250);
FORCEPROP 1 LAST PATH I47
J 0
(-2877 2375);
DISPLAY 0.872340 (-2877 2375);
PAINT GREEN (-2877 2375);
DISPLAY INVISIBLE (-2877 2375);
FORCEADD TAP..1
(-2875 2425);
FORCEPROP 3 LASTPIN (-2925 2425) SIG_NAME TP_P3E_CPU1_PE1_MP_TXP<5>
J 0
(-2915 2435);
DISPLAY 0.659574 (-2915 2435);
PAINT MONO (-2915 2435);
DISPLAY INVISIBLE (-2915 2435);
FORCEPROP 1 LASTPIN (-2925 2425) BN 5
J 0
(-2937 2433);
DISPLAY 0.617021 (-2937 2433);
PAINT GREEN (-2937 2433);
FORCEPROP 2 LAST CDS_LIB mstr_standard
J 2
(-2875 2425);
PAINT MONO (-2875 2425);
DISPLAY INVISIBLE (-2875 2425);
FORCEPROP 1 LAST BODY_TYPE PLUMBING
J 0
(-2875 2475);
DISPLAY 1.446809 (-2875 2475);
PAINT GREEN (-2875 2475);
DISPLAY INVISIBLE (-2875 2475);
FORCEPROP 1 LAST HDL_TAP TRUE
J 0
(-2550 2300);
DISPLAY 1.446809 (-2550 2300);
PAINT GREEN (-2550 2300);
DISPLAY INVISIBLE (-2550 2300);
FORCEPROP 1 LAST PATH I48
J 0
(-2877 2425);
DISPLAY 0.872340 (-2877 2425);
PAINT GREEN (-2877 2425);
DISPLAY INVISIBLE (-2877 2425);
FORCEADD TAP..1
(-2875 2475);
FORCEPROP 3 LASTPIN (-2925 2475) SIG_NAME TP_P3E_CPU1_PE1_MP_TXP<6>
J 0
(-2915 2485);
DISPLAY 0.659574 (-2915 2485);
PAINT MONO (-2915 2485);
DISPLAY INVISIBLE (-2915 2485);
FORCEPROP 1 LASTPIN (-2925 2475) BN 6
J 0
(-2937 2483);
DISPLAY 0.617021 (-2937 2483);
PAINT GREEN (-2937 2483);
FORCEPROP 2 LAST CDS_LIB mstr_standard
J 2
(-2875 2475);
PAINT MONO (-2875 2475);
DISPLAY INVISIBLE (-2875 2475);
FORCEPROP 1 LAST BODY_TYPE PLUMBING
J 0
(-2875 2525);
DISPLAY 1.446809 (-2875 2525);
PAINT GREEN (-2875 2525);
DISPLAY INVISIBLE (-2875 2525);
FORCEPROP 1 LAST HDL_TAP TRUE
J 0
(-2550 2350);
DISPLAY 1.446809 (-2550 2350);
PAINT GREEN (-2550 2350);
DISPLAY INVISIBLE (-2550 2350);
FORCEPROP 1 LAST PATH I49
J 0
(-2877 2475);
DISPLAY 0.872340 (-2877 2475);
PAINT GREEN (-2877 2475);
DISPLAY INVISIBLE (-2877 2475);
FORCEADD TAP..1
R 2
(-5500 1725);
FORCEPROP 3 LASTPIN (-5450 1725) SIG_NAME TP_P3E_CPU1_PE1_MP_RXN<2>
J 0
(-5440 1735);
DISPLAY 0.659574 (-5440 1735);
PAINT MONO (-5440 1735);
DISPLAY INVISIBLE (-5440 1735);
FORCEPROP 1 LASTPIN (-5450 1725) BN 2
J 2
(-5438 1733);
DISPLAY 0.617021 (-5438 1733);
PAINT GREEN (-5438 1733);
FORCEPROP 2 LAST CDS_LIB mstr_standard
J 0
(-5500 1725);
PAINT MONO (-5500 1725);
DISPLAY INVISIBLE (-5500 1725);
FORCEPROP 1 LAST BODY_TYPE PLUMBING
J 2
(-5500 1775);
DISPLAY 1.446809 (-5500 1775);
PAINT GREEN (-5500 1775);
DISPLAY INVISIBLE (-5500 1775);
FORCEPROP 1 LAST HDL_TAP TRUE
J 2
(-5825 1600);
DISPLAY 1.446809 (-5825 1600);
PAINT GREEN (-5825 1600);
DISPLAY INVISIBLE (-5825 1600);
FORCEPROP 1 LAST PATH I5
J 2
(-5498 1725);
DISPLAY 0.872340 (-5498 1725);
PAINT GREEN (-5498 1725);
DISPLAY INVISIBLE (-5498 1725);
FORCEADD TAP..1
(-2725 2275);
FORCEPROP 3 LASTPIN (-2775 2275) SIG_NAME TP_P3E_CPU1_PE1_MP_TXN<7>
J 0
(-2765 2285);
DISPLAY 0.659574 (-2765 2285);
PAINT MONO (-2765 2285);
DISPLAY INVISIBLE (-2765 2285);
FORCEPROP 1 LASTPIN (-2775 2275) BN 7
J 0
(-2787 2283);
DISPLAY 0.617021 (-2787 2283);
PAINT GREEN (-2787 2283);
FORCEPROP 2 LAST CDS_LIB mstr_standard
J 2
(-2725 2275);
PAINT MONO (-2725 2275);
DISPLAY INVISIBLE (-2725 2275);
FORCEPROP 1 LAST BODY_TYPE PLUMBING
J 0
(-2725 2325);
DISPLAY 1.446809 (-2725 2325);
PAINT GREEN (-2725 2325);
DISPLAY INVISIBLE (-2725 2325);
FORCEPROP 1 LAST HDL_TAP TRUE
J 0
(-2400 2150);
DISPLAY 1.446809 (-2400 2150);
PAINT GREEN (-2400 2150);
DISPLAY INVISIBLE (-2400 2150);
FORCEPROP 1 LAST PATH I50
J 0
(-2727 2275);
DISPLAY 0.872340 (-2727 2275);
PAINT GREEN (-2727 2275);
DISPLAY INVISIBLE (-2727 2275);
FORCEADD TAP..1
(-2875 2525);
FORCEPROP 3 LASTPIN (-2925 2525) SIG_NAME TP_P3E_CPU1_PE1_MP_TXP<7>
J 0
(-2915 2535);
DISPLAY 0.659574 (-2915 2535);
PAINT MONO (-2915 2535);
DISPLAY INVISIBLE (-2915 2535);
FORCEPROP 1 LASTPIN (-2925 2525) BN 7
J 0
(-2937 2533);
DISPLAY 0.617021 (-2937 2533);
PAINT GREEN (-2937 2533);
FORCEPROP 2 LAST CDS_LIB mstr_standard
J 2
(-2875 2525);
PAINT MONO (-2875 2525);
DISPLAY INVISIBLE (-2875 2525);
FORCEPROP 1 LAST BODY_TYPE PLUMBING
J 0
(-2875 2575);
DISPLAY 1.446809 (-2875 2575);
PAINT GREEN (-2875 2575);
DISPLAY INVISIBLE (-2875 2575);
FORCEPROP 1 LAST HDL_TAP TRUE
J 0
(-2550 2400);
DISPLAY 1.446809 (-2550 2400);
PAINT GREEN (-2550 2400);
DISPLAY INVISIBLE (-2550 2400);
FORCEPROP 1 LAST PATH I51
J 0
(-2877 2525);
DISPLAY 0.872340 (-2877 2525);
PAINT GREEN (-2877 2525);
DISPLAY INVISIBLE (-2877 2525);
FORCEADD TAP..1
(-2725 2625);
FORCEPROP 3 LASTPIN (-2775 2625) SIG_NAME TP_P3E_CPU1_PE1_RSR3_TXN<8>
J 0
(-2765 2635);
DISPLAY 0.659574 (-2765 2635);
PAINT MONO (-2765 2635);
DISPLAY INVISIBLE (-2765 2635);
FORCEPROP 1 LASTPIN (-2775 2625) BN 8
J 0
(-2787 2633);
DISPLAY 0.617021 (-2787 2633);
PAINT GREEN (-2787 2633);
FORCEPROP 2 LAST CDS_LIB mstr_standard
J 2
(-2725 2625);
PAINT MONO (-2725 2625);
DISPLAY INVISIBLE (-2725 2625);
FORCEPROP 1 LAST BODY_TYPE PLUMBING
J 0
(-2725 2675);
DISPLAY 1.446809 (-2725 2675);
PAINT GREEN (-2725 2675);
DISPLAY INVISIBLE (-2725 2675);
FORCEPROP 1 LAST HDL_TAP TRUE
J 0
(-2400 2500);
DISPLAY 1.446809 (-2400 2500);
PAINT GREEN (-2400 2500);
DISPLAY INVISIBLE (-2400 2500);
FORCEPROP 1 LAST PATH I52
J 0
(-2727 2625);
DISPLAY 0.872340 (-2727 2625);
PAINT GREEN (-2727 2625);
DISPLAY INVISIBLE (-2727 2625);
FORCEADD TAP..1
(-2725 2725);
FORCEPROP 3 LASTPIN (-2775 2725) SIG_NAME TP_P3E_CPU1_PE1_RSR3_TXN<10>
J 0
(-2765 2735);
DISPLAY 0.659574 (-2765 2735);
PAINT MONO (-2765 2735);
DISPLAY INVISIBLE (-2765 2735);
FORCEPROP 1 LASTPIN (-2775 2725) BN 10
J 0
(-2787 2733);
DISPLAY 0.617021 (-2787 2733);
PAINT GREEN (-2787 2733);
FORCEPROP 2 LAST CDS_LIB mstr_standard
J 2
(-2725 2725);
PAINT MONO (-2725 2725);
DISPLAY INVISIBLE (-2725 2725);
FORCEPROP 1 LAST BODY_TYPE PLUMBING
J 0
(-2725 2775);
DISPLAY 1.446809 (-2725 2775);
PAINT GREEN (-2725 2775);
DISPLAY INVISIBLE (-2725 2775);
FORCEPROP 1 LAST HDL_TAP TRUE
J 0
(-2400 2600);
DISPLAY 1.446809 (-2400 2600);
PAINT GREEN (-2400 2600);
DISPLAY INVISIBLE (-2400 2600);
FORCEPROP 1 LAST PATH I53
J 0
(-2727 2725);
DISPLAY 0.872340 (-2727 2725);
PAINT GREEN (-2727 2725);
DISPLAY INVISIBLE (-2727 2725);
FORCEADD TAP..1
(-2725 2675);
FORCEPROP 3 LASTPIN (-2775 2675) SIG_NAME TP_P3E_CPU1_PE1_RSR3_TXN<9>
J 0
(-2765 2685);
DISPLAY 0.659574 (-2765 2685);
PAINT MONO (-2765 2685);
DISPLAY INVISIBLE (-2765 2685);
FORCEPROP 1 LASTPIN (-2775 2675) BN 9
J 0
(-2787 2683);
DISPLAY 0.617021 (-2787 2683);
PAINT GREEN (-2787 2683);
FORCEPROP 2 LAST CDS_LIB mstr_standard
J 2
(-2725 2675);
PAINT MONO (-2725 2675);
DISPLAY INVISIBLE (-2725 2675);
FORCEPROP 1 LAST BODY_TYPE PLUMBING
J 0
(-2725 2725);
DISPLAY 1.446809 (-2725 2725);
PAINT GREEN (-2725 2725);
DISPLAY INVISIBLE (-2725 2725);
FORCEPROP 1 LAST HDL_TAP TRUE
J 0
(-2400 2550);
DISPLAY 1.446809 (-2400 2550);
PAINT GREEN (-2400 2550);
DISPLAY INVISIBLE (-2400 2550);
FORCEPROP 1 LAST PATH I54
J 0
(-2727 2675);
DISPLAY 0.872340 (-2727 2675);
PAINT GREEN (-2727 2675);
DISPLAY INVISIBLE (-2727 2675);
FORCEADD TAP..1
(-2875 2875);
FORCEPROP 3 LASTPIN (-2925 2875) SIG_NAME TP_P3E_CPU1_PE1_RSR3_TXP<8>
J 0
(-2915 2885);
DISPLAY 0.659574 (-2915 2885);
PAINT MONO (-2915 2885);
DISPLAY INVISIBLE (-2915 2885);
FORCEPROP 1 LASTPIN (-2925 2875) BN 8
J 0
(-2937 2883);
DISPLAY 0.617021 (-2937 2883);
PAINT GREEN (-2937 2883);
FORCEPROP 2 LAST CDS_LIB mstr_standard
J 2
(-2875 2875);
PAINT MONO (-2875 2875);
DISPLAY INVISIBLE (-2875 2875);
FORCEPROP 1 LAST BODY_TYPE PLUMBING
J 0
(-2875 2925);
DISPLAY 1.446809 (-2875 2925);
PAINT GREEN (-2875 2925);
DISPLAY INVISIBLE (-2875 2925);
FORCEPROP 1 LAST HDL_TAP TRUE
J 0
(-2550 2750);
DISPLAY 1.446809 (-2550 2750);
PAINT GREEN (-2550 2750);
DISPLAY INVISIBLE (-2550 2750);
FORCEPROP 1 LAST PATH I55
J 0
(-2877 2875);
DISPLAY 0.872340 (-2877 2875);
PAINT GREEN (-2877 2875);
DISPLAY INVISIBLE (-2877 2875);
FORCEADD TAP..1
(-2875 2925);
FORCEPROP 3 LASTPIN (-2925 2925) SIG_NAME TP_P3E_CPU1_PE1_RSR3_TXP<9>
J 0
(-2915 2935);
DISPLAY 0.659574 (-2915 2935);
PAINT MONO (-2915 2935);
DISPLAY INVISIBLE (-2915 2935);
FORCEPROP 1 LASTPIN (-2925 2925) BN 9
J 0
(-2937 2933);
DISPLAY 0.617021 (-2937 2933);
PAINT GREEN (-2937 2933);
FORCEPROP 2 LAST CDS_LIB mstr_standard
J 2
(-2875 2925);
PAINT MONO (-2875 2925);
DISPLAY INVISIBLE (-2875 2925);
FORCEPROP 1 LAST BODY_TYPE PLUMBING
J 0
(-2875 2975);
DISPLAY 1.446809 (-2875 2975);
PAINT GREEN (-2875 2975);
DISPLAY INVISIBLE (-2875 2975);
FORCEPROP 1 LAST HDL_TAP TRUE
J 0
(-2550 2800);
DISPLAY 1.446809 (-2550 2800);
PAINT GREEN (-2550 2800);
DISPLAY INVISIBLE (-2550 2800);
FORCEPROP 1 LAST PATH I56
J 0
(-2877 2925);
DISPLAY 0.872340 (-2877 2925);
PAINT GREEN (-2877 2925);
DISPLAY INVISIBLE (-2877 2925);
FORCEADD TAP..1
(-2875 2975);
FORCEPROP 3 LASTPIN (-2925 2975) SIG_NAME TP_P3E_CPU1_PE1_RSR3_TXP<10>
J 0
(-2915 2985);
DISPLAY 0.659574 (-2915 2985);
PAINT MONO (-2915 2985);
DISPLAY INVISIBLE (-2915 2985);
FORCEPROP 1 LASTPIN (-2925 2975) BN 10
J 0
(-2937 2983);
DISPLAY 0.617021 (-2937 2983);
PAINT GREEN (-2937 2983);
FORCEPROP 2 LAST CDS_LIB mstr_standard
J 2
(-2875 2975);
PAINT MONO (-2875 2975);
DISPLAY INVISIBLE (-2875 2975);
FORCEPROP 1 LAST BODY_TYPE PLUMBING
J 0
(-2875 3025);
DISPLAY 1.446809 (-2875 3025);
PAINT GREEN (-2875 3025);
DISPLAY INVISIBLE (-2875 3025);
FORCEPROP 1 LAST HDL_TAP TRUE
J 0
(-2550 2850);
DISPLAY 1.446809 (-2550 2850);
PAINT GREEN (-2550 2850);
DISPLAY INVISIBLE (-2550 2850);
FORCEPROP 1 LAST PATH I57
J 0
(-2877 2975);
DISPLAY 0.872340 (-2877 2975);
PAINT GREEN (-2877 2975);
DISPLAY INVISIBLE (-2877 2975);
FORCEADD TAP..1
(-2725 2775);
FORCEPROP 3 LASTPIN (-2775 2775) SIG_NAME TP_P3E_CPU1_PE1_RSR3_TXN<11>
J 0
(-2765 2785);
DISPLAY 0.659574 (-2765 2785);
PAINT MONO (-2765 2785);
DISPLAY INVISIBLE (-2765 2785);
FORCEPROP 1 LASTPIN (-2775 2775) BN 11
J 0
(-2787 2783);
DISPLAY 0.617021 (-2787 2783);
PAINT GREEN (-2787 2783);
FORCEPROP 2 LAST CDS_LIB mstr_standard
J 2
(-2725 2775);
PAINT MONO (-2725 2775);
DISPLAY INVISIBLE (-2725 2775);
FORCEPROP 1 LAST BODY_TYPE PLUMBING
J 0
(-2725 2825);
DISPLAY 1.446809 (-2725 2825);
PAINT GREEN (-2725 2825);
DISPLAY INVISIBLE (-2725 2825);
FORCEPROP 1 LAST HDL_TAP TRUE
J 0
(-2400 2650);
DISPLAY 1.446809 (-2400 2650);
PAINT GREEN (-2400 2650);
DISPLAY INVISIBLE (-2400 2650);
FORCEPROP 1 LAST PATH I58
J 0
(-2727 2775);
DISPLAY 0.872340 (-2727 2775);
PAINT GREEN (-2727 2775);
DISPLAY INVISIBLE (-2727 2775);
FORCEADD TAP..1
(-2875 3025);
FORCEPROP 3 LASTPIN (-2925 3025) SIG_NAME TP_P3E_CPU1_PE1_RSR3_TXP<11>
J 0
(-2915 3035);
DISPLAY 0.659574 (-2915 3035);
PAINT MONO (-2915 3035);
DISPLAY INVISIBLE (-2915 3035);
FORCEPROP 1 LASTPIN (-2925 3025) BN 11
J 0
(-2937 3033);
DISPLAY 0.617021 (-2937 3033);
PAINT GREEN (-2937 3033);
FORCEPROP 2 LAST CDS_LIB mstr_standard
J 2
(-2875 3025);
PAINT MONO (-2875 3025);
DISPLAY INVISIBLE (-2875 3025);
FORCEPROP 1 LAST BODY_TYPE PLUMBING
J 0
(-2875 3075);
DISPLAY 1.446809 (-2875 3075);
PAINT GREEN (-2875 3075);
DISPLAY INVISIBLE (-2875 3075);
FORCEPROP 1 LAST HDL_TAP TRUE
J 0
(-2550 2900);
DISPLAY 1.446809 (-2550 2900);
PAINT GREEN (-2550 2900);
DISPLAY INVISIBLE (-2550 2900);
FORCEPROP 1 LAST PATH I59
J 0
(-2877 3025);
DISPLAY 0.872340 (-2877 3025);
PAINT GREEN (-2877 3025);
DISPLAY INVISIBLE (-2877 3025);
FORCEADD TAP..1
R 2
(-5500 1775);
FORCEPROP 3 LASTPIN (-5450 1775) SIG_NAME TP_P3E_CPU1_PE1_MP_RXN<3>
J 0
(-5440 1785);
DISPLAY 0.659574 (-5440 1785);
PAINT MONO (-5440 1785);
DISPLAY INVISIBLE (-5440 1785);
FORCEPROP 1 LASTPIN (-5450 1775) BN 3
J 2
(-5438 1783);
DISPLAY 0.617021 (-5438 1783);
PAINT GREEN (-5438 1783);
FORCEPROP 2 LAST CDS_LIB mstr_standard
J 0
(-5500 1775);
PAINT MONO (-5500 1775);
DISPLAY INVISIBLE (-5500 1775);
FORCEPROP 1 LAST BODY_TYPE PLUMBING
J 2
(-5500 1825);
DISPLAY 1.446809 (-5500 1825);
PAINT GREEN (-5500 1825);
DISPLAY INVISIBLE (-5500 1825);
FORCEPROP 1 LAST HDL_TAP TRUE
J 2
(-5825 1650);
DISPLAY 1.446809 (-5825 1650);
PAINT GREEN (-5825 1650);
DISPLAY INVISIBLE (-5825 1650);
FORCEPROP 1 LAST PATH I6
J 2
(-5498 1775);
DISPLAY 0.872340 (-5498 1775);
PAINT GREEN (-5498 1775);
DISPLAY INVISIBLE (-5498 1775);
FORCEADD TAP..1
(-2725 3125);
FORCEPROP 3 LASTPIN (-2775 3125) SIG_NAME TP_P3E_CPU1_PE1_RSR3_TXN<12>
J 0
(-2765 3135);
DISPLAY 0.659574 (-2765 3135);
PAINT MONO (-2765 3135);
DISPLAY INVISIBLE (-2765 3135);
FORCEPROP 1 LASTPIN (-2775 3125) BN 12
J 0
(-2787 3133);
DISPLAY 0.617021 (-2787 3133);
PAINT GREEN (-2787 3133);
FORCEPROP 2 LAST CDS_LIB mstr_standard
J 2
(-2725 3125);
PAINT MONO (-2725 3125);
DISPLAY INVISIBLE (-2725 3125);
FORCEPROP 1 LAST BODY_TYPE PLUMBING
J 0
(-2725 3175);
DISPLAY 1.446809 (-2725 3175);
PAINT GREEN (-2725 3175);
DISPLAY INVISIBLE (-2725 3175);
FORCEPROP 1 LAST HDL_TAP TRUE
J 0
(-2400 3000);
DISPLAY 1.446809 (-2400 3000);
PAINT GREEN (-2400 3000);
DISPLAY INVISIBLE (-2400 3000);
FORCEPROP 1 LAST PATH I60
J 0
(-2727 3125);
DISPLAY 0.872340 (-2727 3125);
PAINT GREEN (-2727 3125);
DISPLAY INVISIBLE (-2727 3125);
FORCEADD TAP..1
(-2725 3175);
FORCEPROP 3 LASTPIN (-2775 3175) SIG_NAME TP_P3E_CPU1_PE1_RSR3_TXN<13>
J 0
(-2765 3185);
DISPLAY 0.659574 (-2765 3185);
PAINT MONO (-2765 3185);
DISPLAY INVISIBLE (-2765 3185);
FORCEPROP 1 LASTPIN (-2775 3175) BN 13
J 0
(-2787 3183);
DISPLAY 0.617021 (-2787 3183);
PAINT GREEN (-2787 3183);
FORCEPROP 2 LAST CDS_LIB mstr_standard
J 2
(-2725 3175);
PAINT MONO (-2725 3175);
DISPLAY INVISIBLE (-2725 3175);
FORCEPROP 1 LAST BODY_TYPE PLUMBING
J 0
(-2725 3225);
DISPLAY 1.446809 (-2725 3225);
PAINT GREEN (-2725 3225);
DISPLAY INVISIBLE (-2725 3225);
FORCEPROP 1 LAST HDL_TAP TRUE
J 0
(-2400 3050);
DISPLAY 1.446809 (-2400 3050);
PAINT GREEN (-2400 3050);
DISPLAY INVISIBLE (-2400 3050);
FORCEPROP 1 LAST PATH I61
J 0
(-2727 3175);
DISPLAY 0.872340 (-2727 3175);
PAINT GREEN (-2727 3175);
DISPLAY INVISIBLE (-2727 3175);
FORCEADD TAP..1
(-2725 3225);
FORCEPROP 3 LASTPIN (-2775 3225) SIG_NAME TP_P3E_CPU1_PE1_RSR3_TXN<14>
J 0
(-2765 3235);
DISPLAY 0.659574 (-2765 3235);
PAINT MONO (-2765 3235);
DISPLAY INVISIBLE (-2765 3235);
FORCEPROP 1 LASTPIN (-2775 3225) BN 14
J 0
(-2787 3233);
DISPLAY 0.617021 (-2787 3233);
PAINT GREEN (-2787 3233);
FORCEPROP 2 LAST CDS_LIB mstr_standard
J 2
(-2725 3225);
PAINT MONO (-2725 3225);
DISPLAY INVISIBLE (-2725 3225);
FORCEPROP 1 LAST BODY_TYPE PLUMBING
J 0
(-2725 3275);
DISPLAY 1.446809 (-2725 3275);
PAINT GREEN (-2725 3275);
DISPLAY INVISIBLE (-2725 3275);
FORCEPROP 1 LAST HDL_TAP TRUE
J 0
(-2400 3100);
DISPLAY 1.446809 (-2400 3100);
PAINT GREEN (-2400 3100);
DISPLAY INVISIBLE (-2400 3100);
FORCEPROP 1 LAST PATH I62
J 0
(-2727 3225);
DISPLAY 0.872340 (-2727 3225);
PAINT GREEN (-2727 3225);
DISPLAY INVISIBLE (-2727 3225);
FORCEADD TAP..1
(-2875 3375);
FORCEPROP 3 LASTPIN (-2925 3375) SIG_NAME TP_P3E_CPU1_PE1_RSR3_TXP<12>
J 0
(-2915 3385);
DISPLAY 0.659574 (-2915 3385);
PAINT MONO (-2915 3385);
DISPLAY INVISIBLE (-2915 3385);
FORCEPROP 1 LASTPIN (-2925 3375) BN 12
J 0
(-2937 3383);
DISPLAY 0.617021 (-2937 3383);
PAINT GREEN (-2937 3383);
FORCEPROP 2 LAST CDS_LIB mstr_standard
J 2
(-2875 3375);
PAINT MONO (-2875 3375);
DISPLAY INVISIBLE (-2875 3375);
FORCEPROP 1 LAST BODY_TYPE PLUMBING
J 0
(-2875 3425);
DISPLAY 1.446809 (-2875 3425);
PAINT GREEN (-2875 3425);
DISPLAY INVISIBLE (-2875 3425);
FORCEPROP 1 LAST HDL_TAP TRUE
J 0
(-2550 3250);
DISPLAY 1.446809 (-2550 3250);
PAINT GREEN (-2550 3250);
DISPLAY INVISIBLE (-2550 3250);
FORCEPROP 1 LAST PATH I63
J 0
(-2877 3375);
DISPLAY 0.872340 (-2877 3375);
PAINT GREEN (-2877 3375);
DISPLAY INVISIBLE (-2877 3375);
FORCEADD TAP..1
(-2875 3425);
FORCEPROP 3 LASTPIN (-2925 3425) SIG_NAME TP_P3E_CPU1_PE1_RSR3_TXP<13>
J 0
(-2915 3435);
DISPLAY 0.659574 (-2915 3435);
PAINT MONO (-2915 3435);
DISPLAY INVISIBLE (-2915 3435);
FORCEPROP 1 LASTPIN (-2925 3425) BN 13
J 0
(-2937 3433);
DISPLAY 0.617021 (-2937 3433);
PAINT GREEN (-2937 3433);
FORCEPROP 2 LAST CDS_LIB mstr_standard
J 2
(-2875 3425);
PAINT MONO (-2875 3425);
DISPLAY INVISIBLE (-2875 3425);
FORCEPROP 1 LAST BODY_TYPE PLUMBING
J 0
(-2875 3475);
DISPLAY 1.446809 (-2875 3475);
PAINT GREEN (-2875 3475);
DISPLAY INVISIBLE (-2875 3475);
FORCEPROP 1 LAST HDL_TAP TRUE
J 0
(-2550 3300);
DISPLAY 1.446809 (-2550 3300);
PAINT GREEN (-2550 3300);
DISPLAY INVISIBLE (-2550 3300);
FORCEPROP 1 LAST PATH I64
J 0
(-2877 3425);
DISPLAY 0.872340 (-2877 3425);
PAINT GREEN (-2877 3425);
DISPLAY INVISIBLE (-2877 3425);
FORCEADD TAP..1
(-2875 3475);
FORCEPROP 3 LASTPIN (-2925 3475) SIG_NAME TP_P3E_CPU1_PE1_RSR3_TXP<14>
J 0
(-2915 3485);
DISPLAY 0.659574 (-2915 3485);
PAINT MONO (-2915 3485);
DISPLAY INVISIBLE (-2915 3485);
FORCEPROP 1 LASTPIN (-2925 3475) BN 14
J 0
(-2937 3483);
DISPLAY 0.617021 (-2937 3483);
PAINT GREEN (-2937 3483);
FORCEPROP 2 LAST CDS_LIB mstr_standard
J 2
(-2875 3475);
PAINT MONO (-2875 3475);
DISPLAY INVISIBLE (-2875 3475);
FORCEPROP 1 LAST BODY_TYPE PLUMBING
J 0
(-2875 3525);
DISPLAY 1.446809 (-2875 3525);
PAINT GREEN (-2875 3525);
DISPLAY INVISIBLE (-2875 3525);
FORCEPROP 1 LAST HDL_TAP TRUE
J 0
(-2550 3350);
DISPLAY 1.446809 (-2550 3350);
PAINT GREEN (-2550 3350);
DISPLAY INVISIBLE (-2550 3350);
FORCEPROP 1 LAST PATH I65
J 0
(-2877 3475);
DISPLAY 0.872340 (-2877 3475);
PAINT GREEN (-2877 3475);
DISPLAY INVISIBLE (-2877 3475);
FORCEADD TAP..1
(-2725 3275);
FORCEPROP 3 LASTPIN (-2775 3275) SIG_NAME TP_P3E_CPU1_PE1_RSR3_TXN<15>
J 0
(-2765 3285);
DISPLAY 0.659574 (-2765 3285);
PAINT MONO (-2765 3285);
DISPLAY INVISIBLE (-2765 3285);
FORCEPROP 1 LASTPIN (-2775 3275) BN 15
J 0
(-2787 3283);
DISPLAY 0.617021 (-2787 3283);
PAINT GREEN (-2787 3283);
FORCEPROP 2 LAST CDS_LIB mstr_standard
J 2
(-2725 3275);
PAINT MONO (-2725 3275);
DISPLAY INVISIBLE (-2725 3275);
FORCEPROP 1 LAST BODY_TYPE PLUMBING
J 0
(-2725 3325);
DISPLAY 1.446809 (-2725 3325);
PAINT GREEN (-2725 3325);
DISPLAY INVISIBLE (-2725 3325);
FORCEPROP 1 LAST HDL_TAP TRUE
J 0
(-2400 3150);
DISPLAY 1.446809 (-2400 3150);
PAINT GREEN (-2400 3150);
DISPLAY INVISIBLE (-2400 3150);
FORCEPROP 1 LAST PATH I66
J 0
(-2727 3275);
DISPLAY 0.872340 (-2727 3275);
PAINT GREEN (-2727 3275);
DISPLAY INVISIBLE (-2727 3275);
FORCEADD TAP..1
(-2875 3525);
FORCEPROP 3 LASTPIN (-2925 3525) SIG_NAME TP_P3E_CPU1_PE1_RSR3_TXP<15>
J 0
(-2915 3535);
DISPLAY 0.659574 (-2915 3535);
PAINT MONO (-2915 3535);
DISPLAY INVISIBLE (-2915 3535);
FORCEPROP 1 LASTPIN (-2925 3525) BN 15
J 0
(-2937 3533);
DISPLAY 0.617021 (-2937 3533);
PAINT GREEN (-2937 3533);
FORCEPROP 2 LAST CDS_LIB mstr_standard
J 2
(-2875 3525);
PAINT MONO (-2875 3525);
DISPLAY INVISIBLE (-2875 3525);
FORCEPROP 1 LAST BODY_TYPE PLUMBING
J 0
(-2875 3575);
DISPLAY 1.446809 (-2875 3575);
PAINT GREEN (-2875 3575);
DISPLAY INVISIBLE (-2875 3575);
FORCEPROP 1 LAST HDL_TAP TRUE
J 0
(-2550 3400);
DISPLAY 1.446809 (-2550 3400);
PAINT GREEN (-2550 3400);
DISPLAY INVISIBLE (-2550 3400);
FORCEPROP 1 LAST PATH I67
J 0
(-2877 3525);
DISPLAY 0.872340 (-2877 3525);
PAINT GREEN (-2877 3525);
DISPLAY INVISIBLE (-2877 3525);
FORCEADD SKX_EXT_B..10
(-4075 2575);
FORCEPROP 1 LAST LOCATION U2D1
J 0
(-4775 3775);
DISPLAY 0.617021 (-4775 3775);
PAINT AQUA (-4775 3775);
FORCEPROP 1 LAST PART_NUMBER TBD
J 0
(-4775 1425);
DISPLAY 0.617021 (-4775 1425);
PAINT BLUE (-4775 1425);
FORCEPROP 1 LAST MATERIAL IC
J 0
(-4775 3725);
DISPLAY 0.617021 (-4775 3725);
PAINT SKYBLUE (-4775 3725);
FORCEPROP 2 LASTPIN (-3325 3525) $PN EC8
J 0
(-3315 3535);
DISPLAY 0.617021 (-3315 3535);
PAINT ORANGE (-3315 3535);
FORCEPROP 2 LASTPIN (-3325 3475) $PN EB7
J 0
(-3315 3485);
DISPLAY 0.617021 (-3315 3485);
PAINT ORANGE (-3315 3485);
FORCEPROP 2 LASTPIN (-3325 3425) $PN DW6
J 0
(-3315 3435);
DISPLAY 0.617021 (-3315 3435);
PAINT ORANGE (-3315 3435);
FORCEPROP 2 LASTPIN (-3325 3375) $PN DT7
J 0
(-3315 3385);
DISPLAY 0.617021 (-3315 3385);
PAINT ORANGE (-3315 3385);
FORCEPROP 2 LASTPIN (-3325 3025) $PN DV5
J 0
(-3315 3035);
DISPLAY 0.617021 (-3315 3035);
PAINT ORANGE (-3315 3035);
FORCEPROP 2 LASTPIN (-3325 2975) $PN DU4
J 0
(-3315 2985);
DISPLAY 0.617021 (-3315 2985);
PAINT ORANGE (-3315 2985);
FORCEPROP 2 LASTPIN (-3325 2925) $PN DU2
J 0
(-3315 2935);
DISPLAY 0.617021 (-3315 2935);
PAINT ORANGE (-3315 2935);
FORCEPROP 2 LASTPIN (-3325 2875) $PN DR4
J 0
(-3315 2885);
DISPLAY 0.617021 (-3315 2885);
PAINT ORANGE (-3315 2885);
FORCEPROP 2 LASTPIN (-3325 2525) $PN DP3
J 0
(-3315 2535);
DISPLAY 0.617021 (-3315 2535);
PAINT ORANGE (-3315 2535);
FORCEPROP 2 LASTPIN (-3325 2475) $PN DL2
J 0
(-3315 2485);
DISPLAY 0.617021 (-3315 2485);
PAINT ORANGE (-3315 2485);
FORCEPROP 2 LASTPIN (-3325 2425) $PN DH3
J 0
(-3315 2435);
DISPLAY 0.617021 (-3315 2435);
PAINT ORANGE (-3315 2435);
FORCEPROP 2 LASTPIN (-3325 2375) $PN DF3
J 0
(-3315 2385);
DISPLAY 0.617021 (-3315 2385);
PAINT ORANGE (-3315 2385);
FORCEPROP 2 LASTPIN (-3325 2025) $PN DC4
J 0
(-3315 2035);
DISPLAY 0.617021 (-3315 2035);
PAINT ORANGE (-3315 2035);
FORCEPROP 2 LASTPIN (-3325 1975) $PN DD3
J 0
(-3315 1985);
DISPLAY 0.617021 (-3315 1985);
PAINT ORANGE (-3315 1985);
FORCEPROP 2 LASTPIN (-3325 1925) $PN DB1
J 0
(-3315 1935);
DISPLAY 0.617021 (-3315 1935);
PAINT ORANGE (-3315 1935);
FORCEPROP 2 LASTPIN (-3325 1875) $PN CW2
J 0
(-3315 1885);
DISPLAY 0.617021 (-3315 1885);
PAINT ORANGE (-3315 1885);
FORCEPROP 2 LASTPIN (-3325 3275) $PN ED9
J 0
(-3315 3285);
DISPLAY 0.617021 (-3315 3285);
PAINT ORANGE (-3315 3285);
FORCEPROP 2 LASTPIN (-3325 3225) $PN EA8
J 0
(-3315 3235);
DISPLAY 0.617021 (-3315 3235);
PAINT ORANGE (-3315 3235);
FORCEPROP 2 LASTPIN (-3325 3175) $PN DY7
J 0
(-3315 3185);
DISPLAY 0.617021 (-3315 3185);
PAINT ORANGE (-3315 3185);
FORCEPROP 2 LASTPIN (-3325 3125) $PN DV7
J 0
(-3315 3135);
DISPLAY 0.617021 (-3315 3135);
PAINT ORANGE (-3315 3135);
FORCEPROP 2 LASTPIN (-3325 2775) $PN DU6
J 0
(-3315 2785);
DISPLAY 0.617021 (-3315 2785);
PAINT ORANGE (-3315 2785);
FORCEPROP 2 LASTPIN (-3325 2725) $PN DW4
J 0
(-3315 2735);
DISPLAY 0.617021 (-3315 2735);
PAINT ORANGE (-3315 2735);
FORCEPROP 2 LASTPIN (-3325 2675) $PN DV3
J 0
(-3315 2685);
DISPLAY 0.617021 (-3315 2685);
PAINT ORANGE (-3315 2685);
FORCEPROP 2 LASTPIN (-3325 2625) $PN DT5
J 0
(-3315 2635);
DISPLAY 0.617021 (-3315 2635);
PAINT ORANGE (-3315 2635);
FORCEPROP 2 LASTPIN (-3325 2275) $PN DN4
J 0
(-3315 2285);
DISPLAY 0.617021 (-3315 2285);
PAINT ORANGE (-3315 2285);
FORCEPROP 2 LASTPIN (-3325 2225) $PN DM3
J 0
(-3315 2235);
DISPLAY 0.617021 (-3315 2235);
PAINT ORANGE (-3315 2235);
FORCEPROP 2 LASTPIN (-3325 2175) $PN DK3
J 0
(-3315 2185);
DISPLAY 0.617021 (-3315 2185);
PAINT ORANGE (-3315 2185);
FORCEPROP 2 LASTPIN (-3325 2125) $PN DG4
J 0
(-3315 2135);
DISPLAY 0.617021 (-3315 2135);
PAINT ORANGE (-3315 2135);
FORCEPROP 2 LASTPIN (-3325 1775) $PN DE4
J 0
(-3315 1785);
DISPLAY 0.617021 (-3315 1785);
PAINT ORANGE (-3315 1785);
FORCEPROP 2 LASTPIN (-3325 1725) $PN DE2
J 0
(-3315 1735);
DISPLAY 0.617021 (-3315 1735);
PAINT ORANGE (-3315 1735);
FORCEPROP 2 LASTPIN (-3325 1675) $PN DC2
J 0
(-3315 1685);
DISPLAY 0.617021 (-3315 1685);
PAINT ORANGE (-3315 1685);
FORCEPROP 2 LASTPIN (-3325 1625) $PN DA2
J 0
(-3315 1635);
DISPLAY 0.617021 (-3315 1635);
PAINT ORANGE (-3315 1635);
FORCEPROP 2 LASTPIN (-4825 3525) $PN DT15
J 2
(-4835 3535);
DISPLAY 0.617021 (-4835 3535);
PAINT ORANGE (-4835 3535);
FORCEPROP 2 LASTPIN (-4825 3475) $PN DV15
J 2
(-4835 3485);
DISPLAY 0.617021 (-4835 3485);
PAINT ORANGE (-4835 3485);
FORCEPROP 2 LASTPIN (-4825 3425) $PN DY13
J 2
(-4835 3435);
DISPLAY 0.617021 (-4835 3435);
PAINT ORANGE (-4835 3435);
FORCEPROP 2 LASTPIN (-4825 3375) $PN DU12
J 2
(-4835 3385);
DISPLAY 0.617021 (-4835 3385);
PAINT ORANGE (-4835 3385);
FORCEPROP 2 LASTPIN (-4825 3025) $PN DP13
J 2
(-4835 3035);
DISPLAY 0.617021 (-4835 3035);
PAINT ORANGE (-4835 3035);
FORCEPROP 2 LASTPIN (-4825 2975) $PN DR12
J 2
(-4835 2985);
DISPLAY 0.617021 (-4835 2985);
PAINT ORANGE (-4835 2985);
FORCEPROP 2 LASTPIN (-4825 2925) $PN DN10
J 2
(-4835 2935);
DISPLAY 0.617021 (-4835 2935);
PAINT ORANGE (-4835 2935);
FORCEPROP 2 LASTPIN (-4825 2875) $PN DK11
J 2
(-4835 2885);
DISPLAY 0.617021 (-4835 2885);
PAINT ORANGE (-4835 2885);
FORCEPROP 2 LASTPIN (-4825 2525) $PN DL10
J 2
(-4835 2535);
DISPLAY 0.617021 (-4835 2535);
PAINT ORANGE (-4835 2535);
FORCEPROP 2 LASTPIN (-4825 2475) $PN DJ8
J 2
(-4835 2485);
DISPLAY 0.617021 (-4835 2485);
PAINT ORANGE (-4835 2485);
FORCEPROP 2 LASTPIN (-4825 2425) $PN DF9
J 2
(-4835 2435);
DISPLAY 0.617021 (-4835 2435);
PAINT ORANGE (-4835 2435);
FORCEPROP 2 LASTPIN (-4825 2375) $PN DD9
J 2
(-4835 2385);
DISPLAY 0.617021 (-4835 2385);
PAINT ORANGE (-4835 2385);
FORCEPROP 2 LASTPIN (-4825 2025) $PN DA10
J 2
(-4835 2035);
DISPLAY 0.617021 (-4835 2035);
PAINT ORANGE (-4835 2035);
FORCEPROP 2 LASTPIN (-4825 1975) $PN DB9
J 2
(-4835 1985);
DISPLAY 0.617021 (-4835 1985);
PAINT ORANGE (-4835 1985);
FORCEPROP 2 LASTPIN (-4825 1925) $PN CY7
J 2
(-4835 1935);
DISPLAY 0.617021 (-4835 1935);
PAINT ORANGE (-4835 1935);
FORCEPROP 2 LASTPIN (-4825 1875) $PN CU8
J 2
(-4835 1885);
DISPLAY 0.617021 (-4835 1885);
PAINT ORANGE (-4835 1885);
FORCEPROP 2 LASTPIN (-4825 3275) $PN DU16
J 2
(-4835 3285);
DISPLAY 0.617021 (-4835 3285);
PAINT ORANGE (-4835 3285);
FORCEPROP 2 LASTPIN (-4825 3225) $PN DY15
J 2
(-4835 3235);
DISPLAY 0.617021 (-4835 3235);
PAINT ORANGE (-4835 3235);
FORCEPROP 2 LASTPIN (-4825 3175) $PN DW14
J 2
(-4835 3185);
DISPLAY 0.617021 (-4835 3185);
PAINT ORANGE (-4835 3185);
FORCEPROP 2 LASTPIN (-4825 3125) $PN DV13
J 2
(-4835 3135);
DISPLAY 0.617021 (-4835 3135);
PAINT ORANGE (-4835 3135);
FORCEPROP 2 LASTPIN (-4825 2775) $PN DT13
J 2
(-4835 2785);
DISPLAY 0.617021 (-4835 2785);
PAINT ORANGE (-4835 2785);
FORCEPROP 2 LASTPIN (-4825 2725) $PN DT11
J 2
(-4835 2735);
DISPLAY 0.617021 (-4835 2735);
PAINT ORANGE (-4835 2735);
FORCEPROP 2 LASTPIN (-4825 2675) $PN DP11
J 2
(-4835 2685);
DISPLAY 0.617021 (-4835 2685);
PAINT ORANGE (-4835 2685);
FORCEPROP 2 LASTPIN (-4825 2625) $PN DM11
J 2
(-4835 2635);
DISPLAY 0.617021 (-4835 2635);
PAINT ORANGE (-4835 2635);
FORCEPROP 2 LASTPIN (-4825 2275) $PN DM9
J 2
(-4835 2285);
DISPLAY 0.617021 (-4835 2285);
PAINT ORANGE (-4835 2285);
FORCEPROP 2 LASTPIN (-4825 2225) $PN DK9
J 2
(-4835 2235);
DISPLAY 0.617021 (-4835 2235);
PAINT ORANGE (-4835 2235);
FORCEPROP 2 LASTPIN (-4825 2175) $PN DH9
J 2
(-4835 2185);
DISPLAY 0.617021 (-4835 2185);
PAINT ORANGE (-4835 2185);
FORCEPROP 2 LASTPIN (-4825 2125) $PN DE10
J 2
(-4835 2135);
DISPLAY 0.617021 (-4835 2135);
PAINT ORANGE (-4835 2135);
FORCEPROP 2 LASTPIN (-4825 1775) $PN DC10
J 2
(-4835 1785);
DISPLAY 0.617021 (-4835 1785);
PAINT ORANGE (-4835 1785);
FORCEPROP 2 LASTPIN (-4825 1725) $PN DC8
J 2
(-4835 1735);
DISPLAY 0.617021 (-4835 1735);
PAINT ORANGE (-4835 1735);
FORCEPROP 2 LASTPIN (-4825 1675) $PN DA8
J 2
(-4835 1685);
DISPLAY 0.617021 (-4835 1685);
PAINT ORANGE (-4835 1685);
FORCEPROP 2 LASTPIN (-4825 1625) $PN CW8
J 2
(-4835 1635);
DISPLAY 0.617021 (-4835 1635);
PAINT ORANGE (-4835 1635);
FORCEPROP 1 LAST PACK_TYPE BGA1
J 0
(-4775 3825);
PAINT SKYBLUE (-4775 3825);
DISPLAY INVISIBLE (-4775 3825);
FORCEPROP 2 LAST SEC_TYPE BGA1
J 0
(-4775 3825);
DISPLAY 1.021277 (-4775 3825);
PAINT ORANGE (-4775 3825);
DISPLAY INVISIBLE (-4775 3825);
FORCEPROP 2 LAST CDS_LIB chpset_lib
J 0
(-4075 2575);
PAINT ORANGE (-4075 2575);
DISPLAY INVISIBLE (-4075 2575);
FORCEPROP 2 LAST SEC 10
J 0
(-4775 3825);
DISPLAY 0.680851 (-4775 3825);
PAINT MONO (-4775 3825);
DISPLAY INVISIBLE (-4775 3825);
FORCEPROP 2 LAST CDS_LOCATION U2D1
J 0
(-4775 3775);
DISPLAY 0.617021 (-4775 3775);
PAINT AQUA (-4775 3775);
DISPLAY INVISIBLE (-4775 3775);
FORCEPROP 1 LAST PATH I68
J 0
(-4075 3725);
PAINT GREEN (-4075 3725);
DISPLAY INVISIBLE (-4075 3725);
FORCEADD TAP..1
R 2
(-5350 1875);
FORCEPROP 3 LASTPIN (-5300 1875) SIG_NAME TP_P3E_CPU1_PE1_MP_RXP<0>
J 0
(-5290 1885);
DISPLAY 0.659574 (-5290 1885);
PAINT MONO (-5290 1885);
DISPLAY INVISIBLE (-5290 1885);
FORCEPROP 1 LASTPIN (-5300 1875) BN 0
J 2
(-5288 1883);
DISPLAY 0.617021 (-5288 1883);
PAINT GREEN (-5288 1883);
FORCEPROP 2 LAST CDS_LIB mstr_standard
J 0
(-5350 1875);
PAINT MONO (-5350 1875);
DISPLAY INVISIBLE (-5350 1875);
FORCEPROP 1 LAST BODY_TYPE PLUMBING
J 2
(-5350 1925);
DISPLAY 1.446809 (-5350 1925);
PAINT GREEN (-5350 1925);
DISPLAY INVISIBLE (-5350 1925);
FORCEPROP 1 LAST HDL_TAP TRUE
J 2
(-5675 1750);
DISPLAY 1.446809 (-5675 1750);
PAINT GREEN (-5675 1750);
DISPLAY INVISIBLE (-5675 1750);
FORCEPROP 1 LAST PATH I7
J 2
(-5348 1875);
DISPLAY 0.872340 (-5348 1875);
PAINT GREEN (-5348 1875);
DISPLAY INVISIBLE (-5348 1875);
FORCEADD TAP..1
R 2
(-5350 1925);
FORCEPROP 3 LASTPIN (-5300 1925) SIG_NAME TP_P3E_CPU1_PE1_MP_RXP<1>
J 0
(-5290 1935);
DISPLAY 0.659574 (-5290 1935);
PAINT MONO (-5290 1935);
DISPLAY INVISIBLE (-5290 1935);
FORCEPROP 1 LASTPIN (-5300 1925) BN 1
J 2
(-5288 1933);
DISPLAY 0.617021 (-5288 1933);
PAINT GREEN (-5288 1933);
FORCEPROP 2 LAST CDS_LIB mstr_standard
J 0
(-5350 1925);
PAINT MONO (-5350 1925);
DISPLAY INVISIBLE (-5350 1925);
FORCEPROP 1 LAST BODY_TYPE PLUMBING
J 2
(-5350 1975);
DISPLAY 1.446809 (-5350 1975);
PAINT GREEN (-5350 1975);
DISPLAY INVISIBLE (-5350 1975);
FORCEPROP 1 LAST HDL_TAP TRUE
J 2
(-5675 1800);
DISPLAY 1.446809 (-5675 1800);
PAINT GREEN (-5675 1800);
DISPLAY INVISIBLE (-5675 1800);
FORCEPROP 1 LAST PATH I8
J 2
(-5348 1925);
DISPLAY 0.872340 (-5348 1925);
PAINT GREEN (-5348 1925);
DISPLAY INVISIBLE (-5348 1925);
FORCEADD DESIGN_NOTE..1
(-4550 1300);
FORCEPROP 0 LAST L1 CPU SYMBOLS 1-30 ARE PRELIMINARY AND SUBJECT TO CHANGE
J 0
(-4750 1175);
DISPLAY 1.021277 (-4750 1175);
PAINT ORANGE (-4750 1175);
FORCEPROP 2 LAST CDS_LIB mstr_symbols
J 0
(-4550 1300);
PAINT ORANGE (-4550 1300);
DISPLAY INVISIBLE (-4550 1300);
FORCEPROP 1 LAST COMMENT_BODY TRUE
J 0
(-4525 1400);
DISPLAY 0.978723 (-4525 1400);
PAINT ORANGE (-4525 1400);
DISPLAY INVISIBLE (-4525 1400);
FORCEADD INTEL_CORP_BPAGE..1
(0 0);
FORCEPROP 1 LAST CDS_CON_LAST_MODIFIED Fri Jun 16 17:48:25 2017
J 0
(-1425 325);
DISPLAY 1.340426 (-1425 325);
PAINT GREEN (-1425 325);
DISPLAY INVISIBLE (-1425 325);
FORCEPROP 1 LAST CUSTOM_TXT_CDS <CURRENT_DESIGN_SHEET> OF <TOTAL_DESIGN_SHEETS>
J 0
(-500 25);
PAINT ORANGE (-500 25);
FORCEPROP 1 LAST CUSTOM_TXT_CDS <CON_LAST_MODIFIED>
J 0
(-4000 100);
PAINT ORANGE (-4000 100);
FORCEPROP 2 LAST CUSTOM_TXT_CDS <XR_PAGE_TITLE>
J 0
(-7890 5250);
DISPLAY 0.638298 (-7890 5250);
PAINT PINK (-7890 5250);
DISPLAY INVISIBLE (-7890 5250);
FORCEPROP 1 LAST SCH_TITLE SKYLAKE - SKT1 - 10 OF 21
J 0
(-7950 50);
DISPLAY 1.212766 (-7950 50);
PAINT GREEN (-7950 50);
FORCEPROP 2 LAST CDS_LIB mstr_symbols
J 0
(0 0);
PAINT ORANGE (0 0);
DISPLAY INVISIBLE (0 0);
FORCEPROP 2 LAST PAGE_BORDER TRUE
J 0
(-7890 5250);
DISPLAY 0.851064 (-7890 5250);
PAINT PINK (-7890 5250);
DISPLAY INVISIBLE (-7890 5250);
FORCEPROP 1 LAST COMMENT_BODY TRUE
J 0
(12 12);
DISPLAY 0.638298 (12 12);
PAINT GREEN (12 12);
DISPLAY INVISIBLE (12 12);
FORCEPROP 2 LAST CDS_XR_PAGE_TITLE CR-64 : @BASEBOARD_FAB2_LIB.BASEBOARD_FAB2(SCH_1):PAGE64
J 0
(-7890 5250);
DISPLAY 0.638298 (-7890 5250);
PAINT PINK (-7890 5250);
DISPLAY INVISIBLE (-7890 5250);
FORCEADD PRELIM..10
(-4065 2565);
PAINT GRAY (-4065 2565);
FORCEPROP 2 LAST CDS_LIB mstr_misc
J 0
(-4065 2565);
PAINT ORANGE (-4065 2565);
DISPLAY INVISIBLE (-4065 2565);
FORCEPROP 1 LAST COMMENT_BODY TRUE
J 0
(-4065 2565);
PAINT ORANGE (-4065 2565);
DISPLAY INVISIBLE (-4065 2565);
WIRE 17 -1 (-2675 2650)(-2675 2700);
WIRE 17 -1 (-2675 2700)(-2675 2750);
WIRE 17 -1 (-2675 2750)(-2675 2800);
WIRE 17 -1 (-2675 2800)(-2675 3150);
WIRE 17 -1 (-2675 3150)(-2675 3200);
WIRE 17 -1 (-2675 3200)(-2675 3250);
WIRE 17 -1 (-2675 3500)(-1500 3500);
FORCEPROP 2 LAST SIG_NAME TP_P3E_CPU1_PE1_RSR3_TXN<15:8>
J 0
(-2635 3510);
DISPLAY 0.617021 (-2635 3510);
PAINT ORANGE (-2635 3510);
FORCEPROP 2 LASTPROP $XRERR UNIQUE?
J 0
(-1470 3500);
DISPLAY 0.638298 (-1470 3500);
PAINT MONO (-1470 3500);
DISPLAY INVISIBLE (-1470 3500);
WIRE 17 -1 (-2675 3250)(-2675 3300);
WIRE 17 -1 (-2675 3300)(-2675 3500);
WIRE 17 -1 (-2675 1575)(-1700 1575);
FORCEPROP 0 LAST SIG_NAME TP_P3E_CPU1_PE1_MP_TXN<7:0>
J 0
(-2385 1585);
DISPLAY 0.617021 (-2385 1585);
PAINT ORANGE (-2385 1585);
FORCEPROP 2 LASTPROP $XRERR UNIQUE?
J 0
(-1572 1585);
DISPLAY 0.638298 (-1572 1585);
PAINT MONO (-1572 1585);
DISPLAY INVISIBLE (-1572 1585);
WIRE 17 -1 (-2675 1650)(-2675 1575);
WIRE 17 -1 (-2675 1650)(-2675 1700);
WIRE 17 -1 (-2675 1700)(-2675 1750);
WIRE 17 -1 (-2675 1750)(-2675 1800);
WIRE 17 -1 (-2675 1800)(-2675 2150);
WIRE 17 -1 (-2675 2150)(-2675 2200);
WIRE 17 -1 (-2675 2200)(-2675 2250);
WIRE 17 -1 (-2675 2250)(-2675 2300);
WIRE 17 -1 (-2825 2900)(-2825 2950);
WIRE 17 -1 (-2825 2950)(-2825 3000);
WIRE 17 -1 (-2825 3000)(-2825 3050);
WIRE 17 -1 (-2825 3050)(-2825 3400);
WIRE 17 -1 (-2825 3450)(-2825 3400);
WIRE 17 -1 (-2825 3450)(-2825 3500);
WIRE 17 -1 (-2825 3625)(-1500 3625);
FORCEPROP 2 LAST SIG_NAME TP_P3E_CPU1_PE1_RSR3_TXP<15:8>
J 0
(-2635 3635);
DISPLAY 0.617021 (-2635 3635);
PAINT ORANGE (-2635 3635);
FORCEPROP 2 LASTPROP $XRERR UNIQUE?
J 0
(-1470 3625);
DISPLAY 0.638298 (-1470 3625);
PAINT MONO (-1470 3625);
DISPLAY INVISIBLE (-1470 3625);
WIRE 17 -1 (-2825 3500)(-2825 3550);
WIRE 17 -1 (-2825 3550)(-2825 3625);
WIRE 17 -1 (-2825 1425)(-1700 1425);
FORCEPROP 0 LAST SIG_NAME TP_P3E_CPU1_PE1_MP_TXP<7:0>
J 0
(-2385 1435);
DISPLAY 0.617021 (-2385 1435);
PAINT ORANGE (-2385 1435);
FORCEPROP 2 LASTPROP $XRERR UNIQUE?
J 0
(-1572 1435);
DISPLAY 0.638298 (-1572 1435);
PAINT MONO (-1572 1435);
DISPLAY INVISIBLE (-1572 1435);
WIRE 17 -1 (-2825 1900)(-2825 1425);
WIRE 17 -1 (-2825 1950)(-2825 1900);
WIRE 17 -1 (-2825 1950)(-2825 2000);
WIRE 17 -1 (-2825 2000)(-2825 2050);
WIRE 17 -1 (-2825 2050)(-2825 2400);
WIRE 17 -1 (-2825 2400)(-2825 2450);
WIRE 17 -1 (-2825 2450)(-2825 2500);
WIRE 17 -1 (-2825 2500)(-2825 2550);
WIRE 17 -1 (-5550 2700)(-5550 2650);
WIRE 17 -1 (-5550 2750)(-5550 2700);
WIRE 17 -1 (-5550 2800)(-5550 2750);
WIRE 17 -1 (-5550 3150)(-5550 2800);
WIRE 17 -1 (-5550 3200)(-5550 3150);
WIRE 17 -1 (-5550 3250)(-5550 3200);
WIRE 17 -1 (-5550 3250)(-5550 3300);
WIRE 17 -1 (-6700 3500)(-5550 3500);
FORCEPROP 2 LAST SIG_NAME TP_P3E_CPU1_PE1_RSR3_RXN<15:8>
J 0
(-6660 3510);
DISPLAY 0.617021 (-6660 3510);
PAINT ORANGE (-6660 3510);
FORCEPROP 2 LASTPROP $XRERR UNIQUE?
J 0
(-6940 3500);
DISPLAY 0.638298 (-6940 3500);
PAINT MONO (-6940 3500);
DISPLAY INVISIBLE (-6940 3500);
WIRE 17 -1 (-5550 3500)(-5550 3300);
WIRE 17 -1 (-5550 1575)(-6750 1575);
FORCEPROP 0 LAST SIG_NAME TP_P3E_CPU1_PE1_MP_RXN<7:0>
J 0
(-6735 1585);
DISPLAY 0.617021 (-6735 1585);
PAINT ORANGE (-6735 1585);
FORCEPROP 2 LASTPROP $XRERR UNIQUE?
J 0
(-6990 1575);
DISPLAY 0.638298 (-6990 1575);
PAINT MONO (-6990 1575);
DISPLAY INVISIBLE (-6990 1575);
WIRE 17 -1 (-5550 1650)(-5550 1575);
WIRE 17 -1 (-5550 1700)(-5550 1650);
WIRE 17 -1 (-5550 1750)(-5550 1700);
WIRE 17 -1 (-5550 1800)(-5550 1750);
WIRE 17 -1 (-5550 2150)(-5550 1800);
WIRE 17 -1 (-5550 2200)(-5550 2150);
WIRE 17 -1 (-5550 2250)(-5550 2200);
WIRE 17 -1 (-5550 2300)(-5550 2250);
WIRE 17 -1 (-5400 2950)(-5400 2900);
WIRE 17 -1 (-5400 3000)(-5400 2950);
WIRE 17 -1 (-5400 3050)(-5400 3000);
WIRE 17 -1 (-5400 3400)(-5400 3050);
WIRE 17 -1 (-5400 3450)(-5400 3400);
WIRE 17 -1 (-5400 3500)(-5400 3450);
WIRE 17 -1 (-5400 3550)(-5400 3500);
WIRE 17 -1 (-6700 3625)(-5400 3625);
FORCEPROP 2 LAST SIG_NAME TP_P3E_CPU1_PE1_RSR3_RXP<15:8>
J 0
(-6660 3635);
DISPLAY 0.617021 (-6660 3635);
PAINT ORANGE (-6660 3635);
FORCEPROP 2 LASTPROP $XRERR UNIQUE?
J 0
(-6940 3625);
DISPLAY 0.638298 (-6940 3625);
PAINT MONO (-6940 3625);
DISPLAY INVISIBLE (-6940 3625);
WIRE 17 -1 (-5400 3625)(-5400 3550);
WIRE 17 -1 (-5400 1450)(-6750 1450);
FORCEPROP 0 LAST SIG_NAME TP_P3E_CPU1_PE1_MP_RXP<7:0>
J 0
(-6735 1460);
DISPLAY 0.617021 (-6735 1460);
PAINT ORANGE (-6735 1460);
FORCEPROP 2 LASTPROP $XRERR UNIQUE?
J 0
(-6990 1450);
DISPLAY 0.638298 (-6990 1450);
PAINT MONO (-6990 1450);
DISPLAY INVISIBLE (-6990 1450);
WIRE 17 -1 (-5400 1900)(-5400 1450);
WIRE 17 -1 (-5400 1950)(-5400 1900);
WIRE 17 -1 (-5400 2000)(-5400 1950);
WIRE 17 -1 (-5400 2050)(-5400 2000);
WIRE 17 -1 (-5400 2400)(-5400 2050);
WIRE 17 -1 (-5400 2450)(-5400 2400);
WIRE 17 -1 (-5400 2500)(-5400 2450);
WIRE 17 -1 (-5400 2550)(-5400 2500);
WIRE 16 -1 (-2775 3225)(-3325 3225);
WIRE 16 -1 (-5300 2925)(-4825 2925);
WIRE 16 -1 (-5300 3025)(-4825 3025);
WIRE 16 -1 (-5450 3225)(-4825 3225);
WIRE 16 -1 (-5300 2975)(-4825 2975);
WIRE 16 -1 (-5300 1875)(-4825 1875);
WIRE 16 -1 (-5300 1925)(-4825 1925);
WIRE 16 -1 (-5300 1975)(-4825 1975);
WIRE 16 -1 (-5300 2025)(-4825 2025);
WIRE 16 -1 (-5450 1625)(-4825 1625);
WIRE 16 -1 (-5450 1675)(-4825 1675);
WIRE 16 -1 (-5450 1725)(-4825 1725);
WIRE 16 -1 (-5450 1775)(-4825 1775);
WIRE 16 -1 (-5300 2375)(-4825 2375);
WIRE 16 -1 (-5300 2425)(-4825 2425);
WIRE 16 -1 (-5300 2475)(-4825 2475);
WIRE 16 -1 (-5300 2525)(-4825 2525);
WIRE 16 -1 (-5300 2875)(-4825 2875);
WIRE 16 -1 (-5300 3375)(-4825 3375);
WIRE 16 -1 (-4825 3425)(-5300 3425);
WIRE 16 -1 (-5300 3475)(-4825 3475);
WIRE 16 -1 (-5300 3525)(-4825 3525);
WIRE 16 -1 (-5450 2125)(-4825 2125);
WIRE 16 -1 (-5450 2175)(-4825 2175);
WIRE 16 -1 (-4825 2225)(-5450 2225);
WIRE 16 -1 (-5450 2275)(-4825 2275);
WIRE 16 -1 (-5450 2625)(-4825 2625);
WIRE 16 -1 (-5450 2675)(-4825 2675);
WIRE 16 -1 (-5450 2725)(-4825 2725);
WIRE 16 -1 (-5450 2775)(-4825 2775);
WIRE 16 -1 (-5450 3125)(-4825 3125);
WIRE 16 -1 (-5450 3175)(-4825 3175);
WIRE 16 -1 (-5450 3275)(-4825 3275);
WIRE 16 -1 (-3325 1875)(-2925 1875);
WIRE 16 -1 (-2925 1925)(-3325 1925);
WIRE 16 -1 (-3325 1975)(-2925 1975);
WIRE 16 -1 (-2925 2025)(-3325 2025);
WIRE 16 -1 (-2775 1625)(-3325 1625);
WIRE 16 -1 (-2775 1675)(-3325 1675);
WIRE 16 -1 (-2775 1725)(-3325 1725);
WIRE 16 -1 (-2775 1775)(-3325 1775);
WIRE 16 -1 (-2925 2375)(-3325 2375);
WIRE 16 -1 (-2925 2425)(-3325 2425);
WIRE 16 -1 (-2925 2475)(-3325 2475);
WIRE 16 -1 (-2925 2525)(-3325 2525);
WIRE 16 -1 (-2925 2875)(-3325 2875);
WIRE 16 -1 (-2925 2925)(-3325 2925);
WIRE 16 -1 (-2925 2975)(-3325 2975);
WIRE 16 -1 (-2925 3025)(-3325 3025);
WIRE 16 -1 (-2925 3375)(-3325 3375);
WIRE 16 -1 (-3325 3425)(-2925 3425);
WIRE 16 -1 (-3325 3475)(-2925 3475);
WIRE 16 -1 (-2925 3525)(-3325 3525);
WIRE 16 -1 (-2775 2125)(-3325 2125);
WIRE 16 -1 (-2775 2175)(-3325 2175);
WIRE 16 -1 (-3325 2225)(-2775 2225);
WIRE 16 -1 (-3325 2275)(-2775 2275);
WIRE 16 -1 (-2775 2625)(-3325 2625);
WIRE 16 -1 (-3325 2675)(-2775 2675);
WIRE 16 -1 (-2775 2725)(-3325 2725);
WIRE 16 -1 (-2775 2775)(-3325 2775);
WIRE 16 -1 (-3325 3125)(-2775 3125);
WIRE 16 -1 (-2775 3175)(-3325 3175);
WIRE 16 -1 (-2775 3275)(-3325 3275);
FORCENOTE
BOM_COST=PROC_SOCKET
(-7900 225) 0;
DISPLAY LEFT (-7900 225);
DISPLAY 1.723404 (-7900 225);
PAINT PURPLE (-7900 225);
FORCENOTE
ROOM=CPU1
(-7900 350) 0;
DISPLAY LEFT (-7900 350);
DISPLAY 1.723404 (-7900 350);
PAINT PURPLE (-7900 350);
QUIT
